G04 ================== begin FILE IDENTIFICATION RECORD ==================*
G04 Layout Name:  D:/<user>/Wistron_project/16369-sd/gbr/16369-sd.brd*
G04 Film Name:    DRILL*
G04 File Format:  Gerber RS274X*
G04 File Origin:  Cadence Allegro 16.5-S056*
G04 Origin Date:  Wed Mar 29 13:12:45 2017*
G04 *
G04 Layer:  MANUFACTURING/NCLEGEND-1-4*
G04 Layer:  MANUFACTURING/DRILL SIZE*
G04 Layer:  DRAWING FORMAT/LAYER_PCB_STORY*
G04 Layer:  DRAWING FORMAT/LAYER_DRILL*
G04 Layer:  BOARD GEOMETRY/PANEL_OUTLINE*
G04 *
G04 Offset:    (0.00 0.00)*
G04 Mirror:    No*
G04 Mode:      Positive*
G04 Rotation:  0*
G04 FullContactRelief:  No*
G04 UndefLineWidth:     6.00*
G04 ================== end FILE IDENTIFICATION RECORD ====================*
%FSLAX35Y35*MOIN*%
%IR0*IPPOS*OFA0.00000B0.00000*MIA0B0*SFA1.00000B1.00000*%
%AMMACRO13*
1,1,.006,.005,0.0*
20,1,.006,.005,0.0,-.005,0.0,0.0*
1,1,.006,-.005,0.0*
1,1,.006,0.0,.005*
20,1,.006,0.0,.005,0.0,-.005,0.0*
1,1,.006,0.0,-.005*
1,1,.006,.0025,0.0*
20,1,.006,.0025,0.0,.0025,.005,0.0*
1,1,.006,.0025,.005*
20,1,.006,.0025,.005,.0015,.004,0.0*
1,1,.006,.0015,.004*
1,1,.006,.0015,0.0*
20,1,.006,.0015,0.0,.0035,0.0,0.0*
1,1,.006,.0035,0.0*
%
%ADD13MACRO13*%
%AMMACRO11*
1,1,.006,.006,.006*
20,1,.006,.006,.006,.006,-.006,0.0*
1,1,.006,.006,-.006*
20,1,.006,.006,-.006,-.006,-.006,0.0*
1,1,.006,-.006,-.006*
20,1,.006,-.006,-.006,-.006,.006,0.0*
1,1,.006,-.006,.006*
20,1,.006,-.006,.006,.006,.006,0.0*
1,1,.006,.006,.006*
1,1,.006,-.0019,.002*
20,1,.006,-.0019,.002,-.0013,.0026,0.0*
1,1,.006,-.0013,.0026*
20,1,.006,-.0013,.0026,-.0006,.0029,0.0*
1,1,.006,-.0006,.0029*
20,1,.006,-.0006,.0029,.0002,.003,0.0*
1,1,.006,.0002,.003*
20,1,.006,.0002,.003,.0012,.0028,0.0*
1,1,.006,.0012,.0028*
20,1,.006,.0012,.0028,.0019,.0023,0.0*
1,1,.006,.0019,.0023*
20,1,.006,.0019,.0023,.0021,.0017,0.0*
1,1,.006,.0021,.0017*
20,1,.006,.0021,.0017,.002,.0011,0.0*
1,1,.006,.002,.0011*
20,1,.006,.002,.0011,.0016,.0006,0.0*
1,1,.006,.0016,.0006*
20,1,.006,.0016,.0006,-.0004,-.0004,0.0*
1,1,.006,-.0004,-.0004*
20,1,.006,-.0004,-.0004,-.0013,-.0011,0.0*
1,1,.006,-.0013,-.0011*
20,1,.006,-.0013,-.0011,-.0019,-.0021,0.0*
1,1,.006,-.0019,-.0021*
20,1,.006,-.0019,-.0021,-.0021,-.003,0.0*
1,1,.006,-.0021,-.003*
20,1,.006,-.0021,-.003,.0021,-.003,0.0*
1,1,.006,.0021,-.003*
%
%ADD11MACRO11*%
%AMMACRO14*
1,1,.006,.006627,-.016*
20,1,.006,.006627,-.016,-.006627,-.016,0.0*
1,1,.006,-.006627,-.016*
20,1,.006,-.006627,-.016,-.016,-.006627,0.0*
1,1,.006,-.016,-.006627*
20,1,.006,-.016,-.006627,-.016,.006627,0.0*
1,1,.006,-.016,.006627*
20,1,.006,-.016,.006627,-.006627,.016,0.0*
1,1,.006,-.006627,.016*
20,1,.006,-.006627,.016,.006627,.016,0.0*
1,1,.006,.006627,.016*
20,1,.006,.006627,.016,.016,.006627,0.0*
1,1,.006,.016,.006627*
20,1,.006,.016,.006627,.016,-.006627,0.0*
1,1,.006,.016,-.006627*
20,1,.006,.016,-.006627,.006627,-.016,0.0*
1,1,.006,.006627,-.016*
1,1,.006,-.00587,-.0056*
20,1,.006,-.00587,-.0056,-.00427,-.00693,0.0*
1,1,.006,-.00427,-.00693*
20,1,.006,-.00427,-.00693,-.0024,-.00773,0.0*
1,1,.006,-.0024,-.00773*
20,1,.006,-.0024,-.00773,0.0,-.008,0.0*
1,1,.006,0.0,-.008*
20,1,.006,0.0,-.008,.0024,-.00747,0.0*
1,1,.006,.0024,-.00747*
20,1,.006,.0024,-.00747,.00427,-.0064,0.0*
1,1,.006,.00427,-.0064*
20,1,.006,.00427,-.0064,.0056,-.00453,0.0*
1,1,.006,.0056,-.00453*
20,1,.006,.0056,-.00453,.00587,-.0024,0.0*
1,1,.006,.00587,-.0024*
20,1,.006,.00587,-.0024,.00533,-.00027,0.0*
1,1,.006,.00533,-.00027*
20,1,.006,.00533,-.00027,.004,.00107,0.0*
1,1,.006,.004,.00107*
20,1,.006,.004,.00107,.00213,.00213,0.0*
1,1,.006,.00213,.00213*
20,1,.006,.00213,.00213,.00027,.0024,0.0*
1,1,.006,.00027,.0024*
20,1,.006,.00027,.0024,-.0016,.00213,0.0*
1,1,.006,-.0016,.00213*
20,1,.006,-.0016,.00213,-.004,.00107,0.0*
1,1,.006,-.004,.00107*
20,1,.006,-.004,.00107,-.0032,.008,0.0*
1,1,.006,-.0032,.008*
20,1,.006,-.0032,.008,.004,.008,0.0*
1,1,.006,.004,.008*
%
%ADD14MACRO14*%
%AMMACRO18*
1,1,.006,.018,0.0*
20,1,.006,.018,0.0,0.0,-.018,0.0*
1,1,.006,0.0,-.018*
20,1,.006,0.0,-.018,-.018,0.0,0.0*
1,1,.006,-.018,0.0*
20,1,.006,-.018,0.0,0.0,.018,0.0*
1,1,.006,0.0,.018*
20,1,.006,0.0,.018,.018,0.0,0.0*
1,1,.006,.018,0.0*
1,1,.006,-.0057,-.0015*
20,1,.006,-.0057,-.0015,-.0036,.0006,0.0*
1,1,.006,-.0036,.0006*
20,1,.006,-.0036,.0006,-.0018,.0018,0.0*
1,1,.006,-.0018,.0018*
20,1,.006,-.0018,.0018,.0006,.0024,0.0*
1,1,.006,.0006,.0024*
20,1,.006,.0006,.0024,.0027,.0018,0.0*
1,1,.006,.0027,.0018*
20,1,.006,.0027,.0018,.0042,.0006,0.0*
1,1,.006,.0042,.0006*
20,1,.006,.0042,.0006,.0054,-.0012,0.0*
1,1,.006,.0054,-.0012*
20,1,.006,.0054,-.0012,.0057,-.0033,0.0*
1,1,.006,.0057,-.0033*
20,1,.006,.0057,-.0033,.0054,-.0051,0.0*
1,1,.006,.0054,-.0051*
20,1,.006,.0054,-.0051,.0042,-.0069,0.0*
1,1,.006,.0042,-.0069*
20,1,.006,.0042,-.0069,.0024,-.0084,0.0*
1,1,.006,.0024,-.0084*
20,1,.006,.0024,-.0084,.0003,-.009,0.0*
1,1,.006,.0003,-.009*
20,1,.006,.0003,-.009,-.0021,-.0084,0.0*
1,1,.006,-.0021,-.0084*
20,1,.006,-.0021,-.0084,-.0042,-.0066,0.0*
1,1,.006,-.0042,-.0066*
20,1,.006,-.0042,-.0066,-.0054,-.0039,0.0*
1,1,.006,-.0054,-.0039*
20,1,.006,-.0054,-.0039,-.0057,-.0009,0.0*
1,1,.006,-.0057,-.0009*
20,1,.006,-.0057,-.0009,-.0051,.003,0.0*
1,1,.006,-.0051,.003*
20,1,.006,-.0051,.003,-.0042,.0051,0.0*
1,1,.006,-.0042,.0051*
20,1,.006,-.0042,.0051,-.0027,.0072,0.0*
1,1,.006,-.0027,.0072*
20,1,.006,-.0027,.0072,-.0006,.0087,0.0*
1,1,.006,-.0006,.0087*
20,1,.006,-.0006,.0087,.0015,.009,0.0*
1,1,.006,.0015,.009*
20,1,.006,.0015,.009,.0036,.0084,0.0*
1,1,.006,.0036,.0084*
20,1,.006,.0036,.0084,.0051,.0069,0.0*
1,1,.006,.0051,.0069*
%
%ADD18MACRO18*%
%AMMACRO17*
1,1,.006,.008,0.0*
20,1,.006,.008,0.0,.004,.006928,0.0*
1,1,.006,.004,.006928*
20,1,.006,.004,.006928,-.004,.006928,0.0*
1,1,.006,-.004,.006928*
20,1,.006,-.004,.006928,-.008,0.0,0.0*
1,1,.006,-.008,0.0*
20,1,.006,-.008,0.0,-.004,-.006928,0.0*
1,1,.006,-.004,-.006928*
20,1,.006,-.004,-.006928,.004,-.006928,0.0*
1,1,.006,.004,-.006928*
20,1,.006,.004,-.006928,.008,0.0,0.0*
1,1,.006,.008,0.0*
1,1,.006,-.00293,-.0024*
20,1,.006,-.00293,-.0024,-.00213,-.00333,0.0*
1,1,.006,-.00213,-.00333*
20,1,.006,-.00213,-.00333,-.00107,-.00387,0.0*
1,1,.006,-.00107,-.00387*
20,1,.006,-.00107,-.00387,.00013,-.004,0.0*
1,1,.006,.00013,-.004*
20,1,.006,.00013,-.004,.0012,-.00387,0.0*
1,1,.006,.0012,-.00387*
20,1,.006,.0012,-.00387,.00227,-.0032,0.0*
1,1,.006,.00227,-.0032*
20,1,.006,.00227,-.0032,.00293,-.0024,0.0*
1,1,.006,.00293,-.0024*
20,1,.006,.00293,-.0024,.00307,-.0016,0.0*
1,1,.006,.00307,-.0016*
20,1,.006,.00307,-.0016,.0028,-.00067,0.0*
1,1,.006,.0028,-.00067*
20,1,.006,.0028,-.00067,.00187,0.0,0.0*
1,1,.006,.00187,0.0*
20,1,.006,.00187,0.0,.00093,.00027,0.0*
1,1,.006,.00093,.00027*
20,1,.006,.00093,.00027,-.00027,.00027,0.0*
1,1,.006,-.00027,.00027*
1,1,.006,.00093,.00027*
20,1,.006,.00093,.00027,.00173,.00067,0.0*
1,1,.006,.00173,.00067*
20,1,.006,.00173,.00067,.0024,.00133,0.0*
1,1,.006,.0024,.00133*
20,1,.006,.0024,.00133,.00267,.00213,0.0*
1,1,.006,.00267,.00213*
20,1,.006,.00267,.00213,.0024,.00293,0.0*
1,1,.006,.0024,.00293*
20,1,.006,.0024,.00293,.00173,.0036,0.0*
1,1,.006,.00173,.0036*
20,1,.006,.00173,.0036,.00053,.004,0.0*
1,1,.006,.00053,.004*
20,1,.006,.00053,.004,-.00067,.00387,0.0*
1,1,.006,-.00067,.00387*
20,1,.006,-.00067,.00387,-.00187,.00333,0.0*
1,1,.006,-.00187,.00333*
%
%ADD17MACRO17*%
%AMMACRO19*
1,1,.006,-.028,.084*
20,1,.006,-.028,.084,.028,.084,0.0*
1,1,.006,.028,.084*
20,1,.006,.028,.084,.042586,.082724,0.0*
1,1,.006,.042586,.082724*
20,1,.006,.042586,.082724,.05673,.078934,0.0*
1,1,.006,.05673,.078934*
20,1,.006,.05673,.078934,.07,.072746,0.0*
1,1,.006,.07,.072746*
20,1,.006,.07,.072746,.081994,.064348,0.0*
1,1,.006,.081994,.064348*
20,1,.006,.081994,.064348,.092348,.053994,0.0*
1,1,.006,.092348,.053994*
20,1,.006,.092348,.053994,.100746,.042,0.0*
1,1,.006,.100746,.042*
20,1,.006,.100746,.042,.106934,.02873,0.0*
1,1,.006,.106934,.02873*
20,1,.006,.106934,.02873,.110724,.014586,0.0*
1,1,.006,.110724,.014586*
20,1,.006,.110724,.014586,.112,0.0,0.0*
1,1,.006,.112,0.0*
20,1,.006,.112,0.0,.110724,-.014586,0.0*
1,1,.006,.110724,-.014586*
20,1,.006,.110724,-.014586,.106934,-.02873,0.0*
1,1,.006,.106934,-.02873*
20,1,.006,.106934,-.02873,.100746,-.042,0.0*
1,1,.006,.100746,-.042*
20,1,.006,.100746,-.042,.092348,-.053994,0.0*
1,1,.006,.092348,-.053994*
20,1,.006,.092348,-.053994,.081994,-.064348,0.0*
1,1,.006,.081994,-.064348*
20,1,.006,.081994,-.064348,.07,-.072746,0.0*
1,1,.006,.07,-.072746*
20,1,.006,.07,-.072746,.05673,-.078934,0.0*
1,1,.006,.05673,-.078934*
20,1,.006,.05673,-.078934,.042586,-.082724,0.0*
1,1,.006,.042586,-.082724*
20,1,.006,.042586,-.082724,.028,-.084,0.0*
1,1,.006,.028,-.084*
20,1,.006,.028,-.084,-.028,-.084,0.0*
1,1,.006,-.028,-.084*
20,1,.006,-.028,-.084,-.042586,-.082724,0.0*
1,1,.006,-.042586,-.082724*
20,1,.006,-.042586,-.082724,-.05673,-.078934,0.0*
1,1,.006,-.05673,-.078934*
20,1,.006,-.05673,-.078934,-.07,-.072746,0.0*
1,1,.006,-.07,-.072746*
20,1,.006,-.07,-.072746,-.081994,-.064348,0.0*
1,1,.006,-.081994,-.064348*
20,1,.006,-.081994,-.064348,-.092348,-.053994,0.0*
1,1,.006,-.092348,-.053994*
20,1,.006,-.092348,-.053994,-.100746,-.042,0.0*
1,1,.006,-.100746,-.042*
20,1,.006,-.100746,-.042,-.106934,-.02873,0.0*
1,1,.006,-.106934,-.02873*
20,1,.006,-.106934,-.02873,-.110724,-.014586,0.0*
1,1,.006,-.110724,-.014586*
20,1,.006,-.110724,-.014586,-.112,0.0,0.0*
1,1,.006,-.112,0.0*
20,1,.006,-.112,0.0,-.110724,.014586,0.0*
1,1,.006,-.110724,.014586*
20,1,.006,-.110724,.014586,-.106934,.02873,0.0*
1,1,.006,-.106934,.02873*
20,1,.006,-.106934,.02873,-.100746,.042,0.0*
1,1,.006,-.100746,.042*
20,1,.006,-.100746,.042,-.092348,.053994,0.0*
1,1,.006,-.092348,.053994*
20,1,.006,-.092348,.053994,-.081994,.064348,0.0*
1,1,.006,-.081994,.064348*
20,1,.006,-.081994,.064348,-.07,.072746,0.0*
1,1,.006,-.07,.072746*
20,1,.006,-.07,.072746,-.05673,.078934,0.0*
1,1,.006,-.05673,.078934*
20,1,.006,-.05673,.078934,-.042586,.082724,0.0*
1,1,.006,-.042586,.082724*
20,1,.006,-.042586,.082724,-.028,.084,0.0*
1,1,.006,-.028,.084*
1,1,.006,0.0,-.042*
20,1,.006,0.0,-.042,.0098,-.0406,0.0*
1,1,.006,.0098,-.0406*
20,1,.006,.0098,-.0406,.021,-.0364,0.0*
1,1,.006,.021,-.0364*
20,1,.006,.021,-.0364,.028,-.0294,0.0*
1,1,.006,.028,-.0294*
20,1,.006,.028,-.0294,.0308,-.0196,0.0*
1,1,.006,.0308,-.0196*
20,1,.006,.0308,-.0196,.028,-.0098,0.0*
1,1,.006,.028,-.0098*
20,1,.006,.028,-.0098,.0196,-.0014,0.0*
1,1,.006,.0196,-.0014*
20,1,.006,.0196,-.0014,.007,.0028,0.0*
1,1,.006,.007,.0028*
20,1,.006,.007,.0028,-.007,.0028,0.0*
1,1,.006,-.007,.0028*
20,1,.006,-.007,.0028,-.0154,.0056,0.0*
1,1,.006,-.0154,.0056*
20,1,.006,-.0154,.0056,-.0224,.0126,0.0*
1,1,.006,-.0224,.0126*
20,1,.006,-.0224,.0126,-.0252,.0224,0.0*
1,1,.006,-.0252,.0224*
20,1,.006,-.0252,.0224,-.021,.0322,0.0*
1,1,.006,-.021,.0322*
20,1,.006,-.021,.0322,-.0112,.0392,0.0*
1,1,.006,-.0112,.0392*
20,1,.006,-.0112,.0392,0.0,.042,0.0*
1,1,.006,0.0,.042*
20,1,.006,0.0,.042,.0112,.0392,0.0*
1,1,.006,.0112,.0392*
20,1,.006,.0112,.0392,.021,.0322,0.0*
1,1,.006,.021,.0322*
20,1,.006,.021,.0322,.0252,.0224,0.0*
1,1,.006,.0252,.0224*
20,1,.006,.0252,.0224,.0224,.0126,0.0*
1,1,.006,.0224,.0126*
20,1,.006,.0224,.0126,.0154,.0056,0.0*
1,1,.006,.0154,.0056*
20,1,.006,.0154,.0056,.007,.0028,0.0*
1,1,.006,.007,.0028*
20,1,.006,.007,.0028,-.007,.0028,0.0*
1,1,.006,-.007,.0028*
20,1,.006,-.007,.0028,-.0196,-.0014,0.0*
1,1,.006,-.0196,-.0014*
20,1,.006,-.0196,-.0014,-.028,-.0098,0.0*
1,1,.006,-.028,-.0098*
20,1,.006,-.028,-.0098,-.0308,-.0196,0.0*
1,1,.006,-.0308,-.0196*
20,1,.006,-.0308,-.0196,-.028,-.0294,0.0*
1,1,.006,-.028,-.0294*
20,1,.006,-.028,-.0294,-.021,-.0364,0.0*
1,1,.006,-.021,-.0364*
20,1,.006,-.021,-.0364,-.0098,-.0406,0.0*
1,1,.006,-.0098,-.0406*
20,1,.006,-.0098,-.0406,0.0,-.042,0.0*
1,1,.006,0.0,-.042*
%
%ADD19MACRO19*%
%AMMACRO15*
1,1,.006,0.0,.014*
20,1,.006,0.0,.014,-.012124,.007,0.0*
1,1,.006,-.012124,.007*
20,1,.006,-.012124,.007,-.012124,-.007,0.0*
1,1,.006,-.012124,-.007*
20,1,.006,-.012124,-.007,0.0,-.014,0.0*
1,1,.006,0.0,-.014*
20,1,.006,0.0,-.014,.012124,-.007,0.0*
1,1,.006,.012124,-.007*
20,1,.006,.012124,-.007,.012124,.007,0.0*
1,1,.006,.012124,.007*
20,1,.006,.012124,.007,0.0,.014,0.0*
1,1,.006,0.0,.014*
1,1,.006,.0028,-.007*
20,1,.006,.0028,-.007,.0028,.007,0.0*
1,1,.006,.0028,.007*
20,1,.006,.0028,.007,-.00583,-.00303,0.0*
1,1,.006,-.00583,-.00303*
20,1,.006,-.00583,-.00303,.00583,-.00303,0.0*
1,1,.006,.00583,-.00303*
%
%ADD15MACRO15*%
%AMMACRO12*
1,1,.006,-.0195,.0065*
20,1,.006,-.0195,.0065,-.019204,.009886,0.0*
1,1,.006,-.019204,.009886*
20,1,.006,-.019204,.009886,-.018324,.013169,0.0*
1,1,.006,-.018324,.013169*
20,1,.006,-.018324,.013169,-.016887,.01625,0.0*
1,1,.006,-.016887,.01625*
20,1,.006,-.016887,.01625,-.014938,.019034,0.0*
1,1,.006,-.014938,.019034*
20,1,.006,-.014938,.019034,-.012534,.021438,0.0*
1,1,.006,-.012534,.021438*
20,1,.006,-.012534,.021438,-.00975,.023387,0.0*
1,1,.006,-.00975,.023387*
20,1,.006,-.00975,.023387,-.006669,.024824,0.0*
1,1,.006,-.006669,.024824*
20,1,.006,-.006669,.024824,-.003386,.025704,0.0*
1,1,.006,-.003386,.025704*
20,1,.006,-.003386,.025704,0.0,.026,0.0*
1,1,.006,0.0,.026*
20,1,.006,0.0,.026,.003386,.025704,0.0*
1,1,.006,.003386,.025704*
20,1,.006,.003386,.025704,.006669,.024824,0.0*
1,1,.006,.006669,.024824*
20,1,.006,.006669,.024824,.00975,.023387,0.0*
1,1,.006,.00975,.023387*
20,1,.006,.00975,.023387,.012534,.021438,0.0*
1,1,.006,.012534,.021438*
20,1,.006,.012534,.021438,.014938,.019034,0.0*
1,1,.006,.014938,.019034*
20,1,.006,.014938,.019034,.016887,.01625,0.0*
1,1,.006,.016887,.01625*
20,1,.006,.016887,.01625,.018324,.013169,0.0*
1,1,.006,.018324,.013169*
20,1,.006,.018324,.013169,.019204,.009886,0.0*
1,1,.006,.019204,.009886*
20,1,.006,.019204,.009886,.0195,.0065,0.0*
1,1,.006,.0195,.0065*
20,1,.006,.0195,.0065,.0195,-.0065,0.0*
1,1,.006,.0195,-.0065*
20,1,.006,.0195,-.0065,.019204,-.009886,0.0*
1,1,.006,.019204,-.009886*
20,1,.006,.019204,-.009886,.018324,-.013169,0.0*
1,1,.006,.018324,-.013169*
20,1,.006,.018324,-.013169,.016887,-.01625,0.0*
1,1,.006,.016887,-.01625*
20,1,.006,.016887,-.01625,.014938,-.019034,0.0*
1,1,.006,.014938,-.019034*
20,1,.006,.014938,-.019034,.012534,-.021438,0.0*
1,1,.006,.012534,-.021438*
20,1,.006,.012534,-.021438,.00975,-.023387,0.0*
1,1,.006,.00975,-.023387*
20,1,.006,.00975,-.023387,.006669,-.024824,0.0*
1,1,.006,.006669,-.024824*
20,1,.006,.006669,-.024824,.003386,-.025704,0.0*
1,1,.006,.003386,-.025704*
20,1,.006,.003386,-.025704,0.0,-.026,0.0*
1,1,.006,0.0,-.026*
20,1,.006,0.0,-.026,-.003386,-.025704,0.0*
1,1,.006,-.003386,-.025704*
20,1,.006,-.003386,-.025704,-.006669,-.024824,0.0*
1,1,.006,-.006669,-.024824*
20,1,.006,-.006669,-.024824,-.00975,-.023387,0.0*
1,1,.006,-.00975,-.023387*
20,1,.006,-.00975,-.023387,-.012534,-.021438,0.0*
1,1,.006,-.012534,-.021438*
20,1,.006,-.012534,-.021438,-.014938,-.019034,0.0*
1,1,.006,-.014938,-.019034*
20,1,.006,-.014938,-.019034,-.016887,-.01625,0.0*
1,1,.006,-.016887,-.01625*
20,1,.006,-.016887,-.01625,-.018324,-.013169,0.0*
1,1,.006,-.018324,-.013169*
20,1,.006,-.018324,-.013169,-.019204,-.009886,0.0*
1,1,.006,-.019204,-.009886*
20,1,.006,-.019204,-.009886,-.0195,-.0065,0.0*
1,1,.006,-.0195,-.0065*
20,1,.006,-.0195,-.0065,-.0195,.0065,0.0*
1,1,.006,-.0195,.0065*
1,1,.006,-.00553,-.00748*
20,1,.006,-.00553,-.00748,-.00325,-.0091,0.0*
1,1,.006,-.00325,-.0091*
20,1,.006,-.00325,-.0091,-.00065,-.00975,0.0*
1,1,.006,-.00065,-.00975*
20,1,.006,-.00065,-.00975,.00195,-.0091,0.0*
1,1,.006,.00195,-.0091*
20,1,.006,.00195,-.0091,.00422,-.00715,0.0*
1,1,.006,.00422,-.00715*
20,1,.006,.00422,-.00715,.00585,-.00422,0.0*
1,1,.006,.00585,-.00422*
20,1,.006,.00585,-.00422,.0065,-.0013,0.0*
1,1,.006,.0065,-.0013*
20,1,.006,.0065,-.0013,.0065,.00227,0.0*
1,1,.006,.0065,.00227*
20,1,.006,.0065,.00227,.00585,.0052,0.0*
1,1,.006,.00585,.0052*
20,1,.006,.00585,.0052,.00422,.0078,0.0*
1,1,.006,.00422,.0078*
20,1,.006,.00422,.0078,.00227,.0091,0.0*
1,1,.006,.00227,.0091*
20,1,.006,.00227,.0091,0.0,.00975,0.0*
1,1,.006,0.0,.00975*
20,1,.006,0.0,.00975,-.0026,.0091,0.0*
1,1,.006,-.0026,.0091*
20,1,.006,-.0026,.0091,-.00455,.0078,0.0*
1,1,.006,-.00455,.0078*
20,1,.006,-.00455,.0078,-.00585,.00585,0.0*
1,1,.006,-.00585,.00585*
20,1,.006,-.00585,.00585,-.0065,.00325,0.0*
1,1,.006,-.0065,.00325*
20,1,.006,-.0065,.00325,-.00585,.00098,0.0*
1,1,.006,-.00585,.00098*
20,1,.006,-.00585,.00098,-.00422,-.0013,0.0*
1,1,.006,-.00422,-.0013*
20,1,.006,-.00422,-.0013,-.00227,-.0026,0.0*
1,1,.006,-.00227,-.0026*
20,1,.006,-.00227,-.0026,0.0,-.00293,0.0*
1,1,.006,0.0,-.00293*
20,1,.006,0.0,-.00293,.0026,-.00228,0.0*
1,1,.006,.0026,-.00228*
20,1,.006,.0026,-.00228,.00455,-.00065,0.0*
1,1,.006,.00455,-.00065*
20,1,.006,.00455,-.00065,.0065,.00227,0.0*
1,1,.006,.0065,.00227*
%
%ADD12MACRO12*%
%AMMACRO16*
1,1,.006,0.0,.0455*
20,1,.006,0.0,.0455,.0455,-.0455,0.0*
1,1,.006,.0455,-.0455*
20,1,.006,.0455,-.0455,-.0455,-.0455,0.0*
1,1,.006,-.0455,-.0455*
20,1,.006,-.0455,-.0455,0.0,.0455,0.0*
1,1,.006,0.0,.0455*
1,1,.006,-.00152,-.02275*
20,1,.006,-.00152,-.02275,0.0,-.01289,0.0*
1,1,.006,0.0,-.01289*
20,1,.006,0.0,-.01289,.00228,-.00455,0.0*
1,1,.006,.00228,-.00455*
20,1,.006,.00228,-.00455,.00531,.00303,0.0*
1,1,.006,.00531,.00303*
20,1,.006,.00531,.00303,.0091,.01137,0.0*
1,1,.006,.0091,.01137*
20,1,.006,.0091,.01137,.01517,.02275,0.0*
1,1,.006,.01517,.02275*
20,1,.006,.01517,.02275,-.01517,.02275,0.0*
1,1,.006,-.01517,.02275*
%
%ADD16MACRO16*%
%AMMACRO10*
1,1,.006,.043,.03225*
20,1,.006,.043,.03225,.043,-.03225,0.0*
1,1,.006,.043,-.03225*
20,1,.006,.043,-.03225,-.043,-.03225,0.0*
1,1,.006,-.043,-.03225*
20,1,.006,-.043,-.03225,-.043,.03225,0.0*
1,1,.006,-.043,.03225*
20,1,.006,-.043,.03225,.043,.03225,0.0*
1,1,.006,.043,.03225*
1,1,.006,-.01613,-.01612*
20,1,.006,-.01613,-.01612,-.01613,.01613,0.0*
1,1,.006,-.01613,.01613*
20,1,.006,-.01613,.01613,-.02258,.00968,0.0*
1,1,.006,-.02258,.00968*
1,1,.006,-.02258,-.01612*
20,1,.006,-.02258,-.01612,-.00968,-.01612,0.0*
1,1,.006,-.00968,-.01612*
1,1,.006,.01613,.01613*
20,1,.006,.01613,.01613,.01183,.01506,0.0*
1,1,.006,.01183,.01506*
20,1,.006,.01183,.01506,.00861,.01237,0.0*
1,1,.006,.00861,.01237*
20,1,.006,.00861,.01237,.00646,.00914,0.0*
1,1,.006,.00646,.00914*
20,1,.006,.00646,.00914,.00485,.00484,0.0*
1,1,.006,.00485,.00484*
20,1,.006,.00485,.00484,.00431,0.0,0.0*
1,1,.006,.00431,0.0*
20,1,.006,.00431,0.0,.00485,-.00483,0.0*
1,1,.006,.00485,-.00483*
20,1,.006,.00485,-.00483,.00646,-.00913,0.0*
1,1,.006,.00646,-.00913*
20,1,.006,.00646,-.00913,.00861,-.01236,0.0*
1,1,.006,.00861,-.01236*
20,1,.006,.00861,-.01236,.01183,-.01505,0.0*
1,1,.006,.01183,-.01505*
20,1,.006,.01183,-.01505,.01613,-.01612,0.0*
1,1,.006,.01613,-.01612*
20,1,.006,.01613,-.01612,.02043,-.01505,0.0*
1,1,.006,.02043,-.01505*
20,1,.006,.02043,-.01505,.02366,-.01236,0.0*
1,1,.006,.02366,-.01236*
20,1,.006,.02366,-.01236,.02581,-.00913,0.0*
1,1,.006,.02581,-.00913*
20,1,.006,.02581,-.00913,.02742,-.00483,0.0*
1,1,.006,.02742,-.00483*
20,1,.006,.02742,-.00483,.02796,0.0,0.0*
1,1,.006,.02796,0.0*
20,1,.006,.02796,0.0,.02742,.00484,0.0*
1,1,.006,.02742,.00484*
20,1,.006,.02742,.00484,.02581,.00914,0.0*
1,1,.006,.02581,.00914*
20,1,.006,.02581,.00914,.02366,.01237,0.0*
1,1,.006,.02366,.01237*
20,1,.006,.02366,.01237,.02043,.01506,0.0*
1,1,.006,.02043,.01506*
20,1,.006,.02043,.01506,.01613,.01613,0.0*
1,1,.006,.01613,.01613*
%
%ADD10MACRO10*%
%ADD20C,.02*%
%ADD21C,.006*%
G75*
%LPD*%
G75*
G54D10*
X-18898Y16741D03*
X-17506Y723144D03*
X13800Y60400D03*
X114497Y137176D03*
X115583Y329366D03*
X114497Y525759D03*
X115583Y717948D03*
X218800Y337200D03*
X365520Y-1413D03*
X366606Y190776D03*
X365520Y387169D03*
X366606Y579359D03*
X494816Y713716D03*
X650246Y145861D03*
G54D20*
G01X-351984Y-328833D02*
X-383984D01*
G01X-351984Y-344833D02*
Y-424833D01*
G01D02*
X998716D01*
G01X-355984Y-328833D02*
G02I-12000J0D01*
G01X-361134D02*
G02I-6850J0D01*
G01X-367984Y-344833D02*
Y-312833D01*
G01X-351984Y-344833D02*
X998716D01*
G01X-351984Y-380333D02*
X998716D01*
G01X211216Y-344833D02*
Y-424833D01*
G01X348716Y-344833D02*
Y-424833D01*
G01X463716Y-344833D02*
Y-424833D01*
G01X631216Y-344833D02*
Y-424833D01*
G01X801216Y-344833D02*
Y-424833D01*
G01X998716Y-344833D02*
Y-424833D01*
G01X1026716Y-328833D02*
G02I-12000J0D01*
G01X1021566D02*
G02I-6850J0D01*
G01X1014716Y-344833D02*
Y-312833D01*
G01X1030716Y-328833D02*
X998716D01*
G54D11*
X6000Y-17500D03*
X16090Y-6960D03*
Y-3360D03*
X4100Y12300D03*
X4300Y38700D03*
X21000Y53500D03*
X4629Y64843D03*
X16090Y240D03*
X63938Y11580D03*
X16090Y3840D03*
X70600Y122500D03*
X65600Y128100D03*
X42600Y129000D03*
X22383Y128937D03*
X20200Y116600D03*
X6220Y219509D03*
X51500Y187600D03*
X51400Y195600D03*
X56755Y199384D03*
X26700Y189160D03*
X22598Y150420D03*
X51076Y202657D03*
X51500Y191500D03*
X44100Y154167D03*
X56400Y158800D03*
X5244Y259114D03*
X4333Y242011D03*
X55200Y285022D03*
X98000Y68200D03*
X112900Y51800D03*
X102000Y62400D03*
X134800Y60300D03*
X135800Y70800D03*
X140100Y14000D03*
X78838Y11602D03*
X124300Y99500D03*
X97600Y92200D03*
X94193Y99637D03*
X81634Y111544D03*
X76100Y117800D03*
X87600Y106400D03*
X101600Y99700D03*
X135900Y99400D03*
X146700Y108400D03*
X217340Y-3360D03*
Y-6960D03*
Y240D03*
Y3840D03*
X168858Y12000D03*
X212287Y39469D03*
X154700Y116500D03*
X190700Y127400D03*
X202783Y128937D03*
X215400Y88900D03*
X186100Y186500D03*
X205848Y199637D03*
X219150Y178000D03*
X222450Y199500D03*
X218700Y193900D03*
X222800Y182000D03*
X199600Y156500D03*
X178747Y288699D03*
X182347Y292152D03*
X199557Y292020D03*
X199521Y288390D03*
X220678Y284412D03*
X650246Y370661D03*
G54D21*
G01X-322688Y-405500D02*
X-321814Y-404625D01*
X-321159Y-403167D01*
X-320722Y-401124D01*
X-321159Y-399375D01*
X-322032Y-398208D01*
X-323561Y-397333D01*
X-329456D01*
Y-414833D01*
X-322251D01*
X-320722Y-413667D01*
X-319849Y-411916D01*
X-319412Y-409875D01*
X-319849Y-407833D01*
X-321159Y-406083D01*
X-322688Y-405500D01*
X-329456D01*
G01X-309991Y-414833D02*
Y-403167D01*
G01Y-405500D02*
X-308899Y-404333D01*
X-307807Y-403458D01*
X-306279Y-403167D01*
X-305188Y-403458D01*
X-303877Y-404333D01*
G01X-294019Y-420083D02*
X-292709Y-420666D01*
X-290962Y-420083D01*
X-289871Y-418917D01*
X-288997Y-417458D01*
X-287688Y-412792D01*
X-284849Y-403167D01*
G01X-291836D02*
X-287688Y-412792D01*
G01X-268441Y-404625D02*
X-269969Y-403458D01*
X-271279Y-403167D01*
X-273026Y-403750D01*
X-274336Y-404916D01*
X-275209Y-406958D01*
X-275428Y-409000D01*
X-275209Y-411042D01*
X-274336Y-412792D01*
X-273026Y-414250D01*
X-271279Y-414833D01*
X-269751Y-414250D01*
X-268441Y-413083D01*
G01X-257709Y-406958D02*
X-250722D01*
X-251377Y-404916D01*
X-252469Y-403750D01*
X-253997Y-403167D01*
X-255526Y-403458D01*
X-256836Y-404333D01*
X-257709Y-406375D01*
X-258146Y-408125D01*
Y-409875D01*
X-257709Y-411625D01*
X-256617Y-413375D01*
X-255307Y-414541D01*
X-253779Y-414833D01*
X-252251Y-414250D01*
X-250722Y-412500D01*
G01X-214631Y-398792D02*
X-215941Y-397916D01*
X-217469Y-397333D01*
X-219216D01*
X-221181Y-398208D01*
X-222709Y-399666D01*
X-223801Y-401417D01*
X-224674Y-404333D01*
X-224893Y-406958D01*
X-224456Y-409583D01*
X-223801Y-411333D01*
X-222491Y-413083D01*
X-220962Y-414250D01*
X-219434Y-414833D01*
X-217906D01*
X-216377Y-414250D01*
X-215067Y-413375D01*
X-213975Y-412209D01*
G01X-198004Y-414833D02*
Y-403167D01*
G01Y-405208D02*
X-198877Y-404042D01*
X-200188Y-403458D01*
X-201716Y-403167D01*
X-203244Y-403750D01*
X-204554Y-404916D01*
X-205428Y-406666D01*
X-205864Y-409000D01*
X-205428Y-411333D01*
X-204554Y-413083D01*
X-203244Y-414250D01*
X-201716Y-414833D01*
X-200188Y-414541D01*
X-198877Y-413667D01*
X-198004Y-412500D01*
G01X-188146Y-414833D02*
Y-403167D01*
G01Y-406083D02*
X-187272Y-404625D01*
X-185962Y-403458D01*
X-184216Y-403167D01*
X-182688Y-403458D01*
X-181377Y-404625D01*
X-180722Y-406666D01*
Y-414833D01*
G01X-171519Y-420083D02*
X-170209Y-420666D01*
X-168462Y-420083D01*
X-167371Y-418917D01*
X-166497Y-417458D01*
X-165188Y-412792D01*
X-162349Y-403167D01*
G01X-169336D02*
X-165188Y-412792D01*
G01X-149434Y-414833D02*
X-150744Y-414541D01*
X-152054Y-413375D01*
X-152928Y-411333D01*
X-153364Y-409000D01*
X-152928Y-406666D01*
X-152054Y-404625D01*
X-150744Y-403458D01*
X-149434Y-403167D01*
X-148124Y-403458D01*
X-146814Y-404625D01*
X-145941Y-406666D01*
X-145722Y-409000D01*
X-145941Y-411333D01*
X-146814Y-413375D01*
X-148124Y-414541D01*
X-149434Y-414833D01*
G01X-135646D02*
Y-403167D01*
G01Y-406083D02*
X-134772Y-404625D01*
X-133462Y-403458D01*
X-131716Y-403167D01*
X-130188Y-403458D01*
X-128877Y-404625D01*
X-128222Y-406666D01*
Y-414833D01*
G01X-101082D02*
Y-397333D01*
X-92786D01*
G01X-95842Y-405791D02*
X-101082D01*
G01X-82491Y-414833D02*
Y-403167D01*
G01Y-405500D02*
X-81399Y-404333D01*
X-80307Y-403458D01*
X-78779Y-403167D01*
X-77688Y-403458D01*
X-76377Y-404333D01*
G01X-61934Y-414833D02*
X-63244Y-414541D01*
X-64554Y-413375D01*
X-65428Y-411333D01*
X-65864Y-409000D01*
X-65428Y-406666D01*
X-64554Y-404625D01*
X-63244Y-403458D01*
X-61934Y-403167D01*
X-60624Y-403458D01*
X-59314Y-404625D01*
X-58441Y-406666D01*
X-58222Y-409000D01*
X-58441Y-411333D01*
X-59314Y-413375D01*
X-60624Y-414541D01*
X-61934Y-414833D01*
G01X-48146D02*
Y-403167D01*
G01Y-406083D02*
X-47272Y-404625D01*
X-45962Y-403458D01*
X-44216Y-403167D01*
X-42688Y-403458D01*
X-41377Y-404625D01*
X-40722Y-406666D01*
Y-414833D01*
G01X-26934Y-397333D02*
Y-414833D01*
G01X-29991Y-403167D02*
X-23877D01*
G01X3699Y-414833D02*
Y-397333D01*
X8939D01*
X10686Y-398208D01*
X11996Y-400250D01*
X12433Y-402583D01*
X11996Y-404916D01*
X10904Y-406666D01*
X8939Y-407542D01*
X3699D01*
G01X29496Y-414833D02*
Y-403167D01*
G01Y-405208D02*
X28623Y-404042D01*
X27312Y-403458D01*
X25784Y-403167D01*
X24256Y-403750D01*
X22946Y-404916D01*
X22072Y-406666D01*
X21636Y-409000D01*
X22072Y-411333D01*
X22946Y-413083D01*
X24256Y-414250D01*
X25784Y-414833D01*
X27312Y-414541D01*
X28623Y-413667D01*
X29496Y-412500D01*
G01X39354Y-414833D02*
Y-403167D01*
G01Y-406083D02*
X40228Y-404625D01*
X41538Y-403458D01*
X43284Y-403167D01*
X44812Y-403458D01*
X46123Y-404625D01*
X46778Y-406666D01*
Y-414833D01*
G01X57291Y-406958D02*
X64278D01*
X63623Y-404916D01*
X62531Y-403750D01*
X61003Y-403167D01*
X59474Y-403458D01*
X58164Y-404333D01*
X57291Y-406375D01*
X56854Y-408125D01*
Y-409875D01*
X57291Y-411625D01*
X58383Y-413375D01*
X59693Y-414541D01*
X61221Y-414833D01*
X62749Y-414250D01*
X64278Y-412500D01*
G01X78066Y-414833D02*
Y-397333D01*
G01X114812Y-405500D02*
X115686Y-404625D01*
X116341Y-403167D01*
X116778Y-401124D01*
X116341Y-399375D01*
X115468Y-398208D01*
X113939Y-397333D01*
X108044D01*
Y-414833D01*
X115249D01*
X116778Y-413667D01*
X117651Y-411916D01*
X118088Y-409875D01*
X117651Y-407833D01*
X116341Y-406083D01*
X114812Y-405500D01*
X108044D01*
G01X130566Y-414833D02*
X129256Y-414541D01*
X127946Y-413375D01*
X127072Y-411333D01*
X126636Y-409000D01*
X127072Y-406666D01*
X127946Y-404625D01*
X129256Y-403458D01*
X130566Y-403167D01*
X131876Y-403458D01*
X133186Y-404625D01*
X134059Y-406666D01*
X134278Y-409000D01*
X134059Y-411333D01*
X133186Y-413375D01*
X131876Y-414541D01*
X130566Y-414833D01*
G01X151996D02*
Y-403167D01*
G01Y-405208D02*
X151123Y-404042D01*
X149812Y-403458D01*
X148284Y-403167D01*
X146756Y-403750D01*
X145446Y-404916D01*
X144572Y-406666D01*
X144136Y-409000D01*
X144572Y-411333D01*
X145446Y-413083D01*
X146756Y-414250D01*
X148284Y-414833D01*
X149812Y-414541D01*
X151123Y-413667D01*
X151996Y-412500D01*
G01X162509Y-414833D02*
Y-403167D01*
G01Y-405500D02*
X163601Y-404333D01*
X164693Y-403458D01*
X166221Y-403167D01*
X167312Y-403458D01*
X168623Y-404333D01*
G01X186996Y-397333D02*
Y-414833D01*
G01Y-412209D02*
X186123Y-413667D01*
X184812Y-414541D01*
X183284Y-414833D01*
X181538Y-414250D01*
X180228Y-412792D01*
X179354Y-411042D01*
X179136Y-409000D01*
X179354Y-406958D01*
X180228Y-405208D01*
X181538Y-403750D01*
X183284Y-403167D01*
X184812Y-403458D01*
X185904Y-404042D01*
X186996Y-405208D01*
G01X-111361Y-369833D02*
Y-352333D01*
X-105684Y-366916D01*
X-100007Y-352333D01*
Y-369833D01*
G01X-88184D02*
X-89494Y-369541D01*
X-90804Y-368375D01*
X-91678Y-366333D01*
X-92114Y-364000D01*
X-91678Y-361666D01*
X-90804Y-359625D01*
X-89494Y-358458D01*
X-88184Y-358167D01*
X-86874Y-358458D01*
X-85564Y-359625D01*
X-84691Y-361666D01*
X-84472Y-364000D01*
X-84691Y-366333D01*
X-85564Y-368375D01*
X-86874Y-369541D01*
X-88184Y-369833D01*
G01X-66754Y-352333D02*
Y-369833D01*
G01Y-367209D02*
X-67627Y-368667D01*
X-68938Y-369541D01*
X-70466Y-369833D01*
X-72212Y-369250D01*
X-73522Y-367792D01*
X-74396Y-366042D01*
X-74614Y-364000D01*
X-74396Y-361958D01*
X-73522Y-360208D01*
X-72212Y-358750D01*
X-70466Y-358167D01*
X-68938Y-358458D01*
X-67846Y-359042D01*
X-66754Y-360208D01*
G01X-56459Y-361958D02*
X-49472D01*
X-50127Y-359916D01*
X-51219Y-358750D01*
X-52747Y-358167D01*
X-54276Y-358458D01*
X-55586Y-359333D01*
X-56459Y-361375D01*
X-56896Y-363125D01*
Y-364875D01*
X-56459Y-366625D01*
X-55367Y-368375D01*
X-54057Y-369541D01*
X-52529Y-369833D01*
X-51001Y-369250D01*
X-49472Y-367500D01*
G01X-35684Y-369833D02*
Y-352333D01*
G01X244916Y-414833D02*
Y-397333D01*
X242296Y-400833D01*
G01Y-414833D02*
X247536D01*
G01X258268Y-407542D02*
X259796Y-405500D01*
X261106Y-404333D01*
X262853Y-403750D01*
X264381Y-404333D01*
X265473Y-405500D01*
X266346Y-407250D01*
X266564Y-409291D01*
X266346Y-411042D01*
X265473Y-412792D01*
X264162Y-414250D01*
X262634Y-414833D01*
X260888Y-414250D01*
X259359Y-412500D01*
X258486Y-409875D01*
X258268Y-406958D01*
X258704Y-403167D01*
X259359Y-401124D01*
X260451Y-399083D01*
X261979Y-397625D01*
X263508Y-397333D01*
X265036Y-397916D01*
X266128Y-399375D01*
G01X275113Y-411333D02*
X276422Y-413375D01*
X278169Y-414541D01*
X280134Y-414833D01*
X281881Y-414541D01*
X283628Y-413083D01*
X284719Y-411333D01*
X284938Y-409583D01*
X284501Y-407542D01*
X282973Y-406083D01*
X281444Y-405500D01*
X279479D01*
G01X281444D02*
X282754Y-404625D01*
X283846Y-403167D01*
X284283Y-401417D01*
X283846Y-399666D01*
X282754Y-398208D01*
X280789Y-397333D01*
X278824Y-397625D01*
X276859Y-398792D01*
G01X293268Y-407542D02*
X294796Y-405500D01*
X296106Y-404333D01*
X297853Y-403750D01*
X299381Y-404333D01*
X300473Y-405500D01*
X301346Y-407250D01*
X301564Y-409291D01*
X301346Y-411042D01*
X300473Y-412792D01*
X299162Y-414250D01*
X297634Y-414833D01*
X295888Y-414250D01*
X294359Y-412500D01*
X293486Y-409875D01*
X293268Y-406958D01*
X293704Y-403167D01*
X294359Y-401124D01*
X295451Y-399083D01*
X296979Y-397625D01*
X298508Y-397333D01*
X300036Y-397916D01*
X301128Y-399375D01*
G01X311204Y-412792D02*
X312733Y-414250D01*
X314479Y-414833D01*
X316226Y-414250D01*
X317754Y-412500D01*
X318846Y-409875D01*
X319283Y-407250D01*
Y-404042D01*
X318846Y-401417D01*
X317754Y-399083D01*
X316444Y-397916D01*
X314916Y-397333D01*
X313169Y-397916D01*
X311859Y-399083D01*
X310986Y-400833D01*
X310549Y-403167D01*
X310986Y-405208D01*
X312078Y-407250D01*
X313388Y-408417D01*
X314916Y-408708D01*
X316662Y-408125D01*
X317973Y-406666D01*
X319283Y-404042D01*
G01X231799Y-369833D02*
Y-352333D01*
X237039D01*
X238786Y-353208D01*
X240096Y-355250D01*
X240533Y-357583D01*
X240096Y-359916D01*
X239004Y-361666D01*
X237039Y-362542D01*
X231799D01*
G01X258469Y-353792D02*
X257159Y-352916D01*
X255631Y-352333D01*
X253884D01*
X251919Y-353208D01*
X250391Y-354666D01*
X249299Y-356417D01*
X248426Y-359333D01*
X248207Y-361958D01*
X248644Y-364583D01*
X249299Y-366333D01*
X250609Y-368083D01*
X252138Y-369250D01*
X253666Y-369833D01*
X255194D01*
X256723Y-369250D01*
X258033Y-368375D01*
X259125Y-367209D01*
G01X272912Y-360500D02*
X273786Y-359625D01*
X274441Y-358167D01*
X274878Y-356124D01*
X274441Y-354375D01*
X273568Y-353208D01*
X272039Y-352333D01*
X266144D01*
Y-369833D01*
X273349D01*
X274878Y-368667D01*
X275751Y-366916D01*
X276188Y-364875D01*
X275751Y-362833D01*
X274441Y-361083D01*
X272912Y-360500D01*
X266144D01*
G01X282116Y-375666D02*
X295216D01*
G01X301144Y-369833D02*
Y-352333D01*
X311188Y-369833D01*
Y-352333D01*
G01X323666Y-369833D02*
X321919Y-369541D01*
X320391Y-368375D01*
X319081Y-366625D01*
X318207Y-364583D01*
X317771Y-362250D01*
Y-359916D01*
X318207Y-357583D01*
X319081Y-355541D01*
X320391Y-353792D01*
X321919Y-352625D01*
X323666Y-352333D01*
X325412Y-352625D01*
X326941Y-353792D01*
X328251Y-355541D01*
X329125Y-357583D01*
X329561Y-359916D01*
Y-362250D01*
X329125Y-364583D01*
X328251Y-366625D01*
X326941Y-368375D01*
X325412Y-369541D01*
X323666Y-369833D01*
G01X374507Y-352333D02*
X379966Y-369833D01*
X385425Y-352333D01*
G01X401833Y-369833D02*
X393099D01*
Y-352333D01*
X401833D01*
G01X398339Y-360791D02*
X393099D01*
G01X410599Y-369833D02*
Y-352333D01*
X416058D01*
X417804Y-353208D01*
X418896Y-354375D01*
X419333Y-356708D01*
X418896Y-359042D01*
X417586Y-360500D01*
X416058Y-361375D01*
X410599D01*
G01X416058D02*
X419333Y-369833D01*
G01X432466Y-370416D02*
X432029Y-370125D01*
Y-369541D01*
X432466Y-369250D01*
X432903Y-369541D01*
Y-370125D01*
X432466Y-370416D01*
G01X392881Y-412500D02*
X394628Y-413958D01*
X396593Y-414833D01*
X398339D01*
X400086Y-413958D01*
X401396Y-412500D01*
X402051Y-410458D01*
X401614Y-408417D01*
X400523Y-406666D01*
X398558Y-405500D01*
X395938Y-404916D01*
X394409Y-403750D01*
X393754Y-401708D01*
X394191Y-399666D01*
X395283Y-398208D01*
X396811Y-397333D01*
X398339D01*
X399868Y-397916D01*
X401178Y-399375D01*
G01X410163Y-414833D02*
Y-397333D01*
X414529D01*
X416276Y-398208D01*
X417586Y-399375D01*
X418678Y-401124D01*
X419551Y-403167D01*
X419769Y-406083D01*
X419551Y-409000D01*
X418678Y-411042D01*
X417586Y-412792D01*
X416276Y-413958D01*
X414529Y-414833D01*
X410163D01*
G01X507613D02*
Y-397333D01*
X511979D01*
X513726Y-398208D01*
X515036Y-399375D01*
X516128Y-401124D01*
X517001Y-403167D01*
X517219Y-406083D01*
X517001Y-409000D01*
X516128Y-411042D01*
X515036Y-412792D01*
X513726Y-413958D01*
X511979Y-414833D01*
X507613D01*
G01X525549D02*
Y-397333D01*
X531008D01*
X532754Y-398208D01*
X533846Y-399375D01*
X534283Y-401708D01*
X533846Y-404042D01*
X532536Y-405500D01*
X531008Y-406375D01*
X525549D01*
G01X531008D02*
X534283Y-414833D01*
G01X544796Y-397333D02*
X550036D01*
G01X547416D02*
Y-414833D01*
G01X544796D02*
X550036D01*
G01X560549Y-397333D02*
Y-414833D01*
X569283D01*
G01X578049Y-397333D02*
Y-414833D01*
X586783D01*
G01X508049Y-352333D02*
Y-369833D01*
X516783D01*
G01X533846D02*
Y-358167D01*
G01Y-360208D02*
X532973Y-359042D01*
X531662Y-358458D01*
X530134Y-358167D01*
X528606Y-358750D01*
X527296Y-359916D01*
X526422Y-361666D01*
X525986Y-364000D01*
X526422Y-366333D01*
X527296Y-368083D01*
X528606Y-369250D01*
X530134Y-369833D01*
X531662Y-369541D01*
X532973Y-368667D01*
X533846Y-367500D01*
G01X542831Y-375083D02*
X544141Y-375666D01*
X545888Y-375083D01*
X546979Y-373917D01*
X547853Y-372458D01*
X549162Y-367792D01*
X552001Y-358167D01*
G01X545014D02*
X549162Y-367792D01*
G01X561641Y-361958D02*
X568628D01*
X567973Y-359916D01*
X566881Y-358750D01*
X565353Y-358167D01*
X563824Y-358458D01*
X562514Y-359333D01*
X561641Y-361375D01*
X561204Y-363125D01*
Y-364875D01*
X561641Y-366625D01*
X562733Y-368375D01*
X564043Y-369541D01*
X565571Y-369833D01*
X567099Y-369250D01*
X568628Y-367500D01*
G01X579359Y-369833D02*
Y-358167D01*
G01Y-360500D02*
X580451Y-359333D01*
X581543Y-358458D01*
X583071Y-358167D01*
X584162Y-358458D01*
X585473Y-359333D01*
G01X672466Y-414833D02*
X670719Y-414541D01*
X669191Y-413375D01*
X667881Y-411625D01*
X667007Y-409583D01*
X666571Y-407250D01*
Y-404916D01*
X667007Y-402583D01*
X667881Y-400541D01*
X669191Y-398792D01*
X670719Y-397625D01*
X672466Y-397333D01*
X674212Y-397625D01*
X675741Y-398792D01*
X677051Y-400541D01*
X677925Y-402583D01*
X678361Y-404916D01*
Y-407250D01*
X677925Y-409583D01*
X677051Y-411625D01*
X675741Y-413375D01*
X674212Y-414541D01*
X672466Y-414833D01*
G01X674212Y-410166D02*
X676833Y-414833D01*
G01X685163Y-397333D02*
Y-409875D01*
X686036Y-412500D01*
X687783Y-414250D01*
X689966Y-414833D01*
X692149Y-414250D01*
X693896Y-412500D01*
X694769Y-409875D01*
Y-397333D01*
G01X704846D02*
X710086D01*
G01X707466D02*
Y-414833D01*
G01X704846D02*
X710086D01*
G01X719944D02*
Y-397333D01*
X729988Y-414833D01*
Y-397333D01*
G01X747269Y-398792D02*
X745959Y-397916D01*
X744431Y-397333D01*
X742684D01*
X740719Y-398208D01*
X739191Y-399666D01*
X738099Y-401417D01*
X737226Y-404333D01*
X737007Y-406958D01*
X737444Y-409583D01*
X738099Y-411333D01*
X739409Y-413083D01*
X740938Y-414250D01*
X742466Y-414833D01*
X743994D01*
X745523Y-414250D01*
X746833Y-413375D01*
X747925Y-412209D01*
G01X759966Y-414833D02*
Y-406958D01*
X755599Y-397333D01*
G01X764333D02*
X759966Y-406958D01*
G01X650163Y-369833D02*
Y-352333D01*
X654529D01*
X656276Y-353208D01*
X657586Y-354375D01*
X658678Y-356124D01*
X659551Y-358167D01*
X659769Y-361083D01*
X659551Y-364000D01*
X658678Y-366042D01*
X657586Y-367792D01*
X656276Y-368958D01*
X654529Y-369833D01*
X650163D01*
G01X669191Y-361958D02*
X676178D01*
X675523Y-359916D01*
X674431Y-358750D01*
X672903Y-358167D01*
X671374Y-358458D01*
X670064Y-359333D01*
X669191Y-361375D01*
X668754Y-363125D01*
Y-364875D01*
X669191Y-366625D01*
X670283Y-368375D01*
X671593Y-369541D01*
X673121Y-369833D01*
X674649Y-369250D01*
X676178Y-367500D01*
G01X686691Y-367792D02*
X687783Y-368958D01*
X689311Y-369833D01*
X690621D01*
X691931Y-369250D01*
X692804Y-368375D01*
X693241Y-367209D01*
X693023Y-365458D01*
X692149Y-364583D01*
X688219Y-362833D01*
X687346Y-360791D01*
X687783Y-359333D01*
X688656Y-358458D01*
X689966Y-358167D01*
X691276Y-358458D01*
X692586Y-359333D01*
G01X707466Y-358167D02*
Y-369833D01*
G01Y-353500D02*
X707029Y-353208D01*
Y-352625D01*
X707466Y-352333D01*
X707903Y-352625D01*
Y-353208D01*
X707466Y-353500D01*
G01X721909Y-374208D02*
X723438Y-375375D01*
X725184Y-375666D01*
X726712Y-375375D01*
X728023Y-373917D01*
X728896Y-371875D01*
Y-358167D01*
G01Y-360500D02*
X728023Y-359333D01*
X726712Y-358458D01*
X725184Y-358167D01*
X723438Y-358750D01*
X722346Y-359916D01*
X721472Y-361958D01*
X721036Y-364000D01*
X721254Y-365750D01*
X722128Y-367792D01*
X723438Y-369250D01*
X725184Y-369833D01*
X726494Y-369541D01*
X728023Y-368375D01*
X728896Y-367209D01*
G01X738754Y-369833D02*
Y-358167D01*
G01Y-361083D02*
X739628Y-359625D01*
X740938Y-358458D01*
X742684Y-358167D01*
X744212Y-358458D01*
X745523Y-359625D01*
X746178Y-361666D01*
Y-369833D01*
G01X756691Y-361958D02*
X763678D01*
X763023Y-359916D01*
X761931Y-358750D01*
X760403Y-358167D01*
X758874Y-358458D01*
X757564Y-359333D01*
X756691Y-361375D01*
X756254Y-363125D01*
Y-364875D01*
X756691Y-366625D01*
X757783Y-368375D01*
X759093Y-369541D01*
X760621Y-369833D01*
X762149Y-369250D01*
X763678Y-367500D01*
G01X774409Y-369833D02*
Y-358167D01*
G01Y-360500D02*
X775501Y-359333D01*
X776593Y-358458D01*
X778121Y-358167D01*
X779212Y-358458D01*
X780523Y-359333D01*
G01X606381Y101811D02*
Y114311D01*
X613511Y101811D01*
Y114311D01*
G01X622346Y101811D02*
X621416Y102019D01*
X620486Y102852D01*
X619866Y104311D01*
X619556Y105978D01*
X619866Y107644D01*
X620486Y109103D01*
X621416Y109936D01*
X622346Y110144D01*
X623276Y109936D01*
X624206Y109103D01*
X624826Y107644D01*
X624981Y105978D01*
X624826Y104311D01*
X624206Y102852D01*
X623276Y102019D01*
X622346Y101811D01*
G01X634746Y114311D02*
Y101811D01*
G01X632576Y110144D02*
X636916D01*
G01X644821Y107436D02*
X649781D01*
X649316Y108894D01*
X648541Y109728D01*
X647456Y110144D01*
X646371Y109936D01*
X645441Y109311D01*
X644821Y107853D01*
X644511Y106602D01*
Y105353D01*
X644821Y104103D01*
X645596Y102852D01*
X646526Y102019D01*
X647611Y101811D01*
X648696Y102228D01*
X649781Y103477D01*
G01X659546Y101394D02*
X659236Y101603D01*
Y102019D01*
X659546Y102228D01*
X659856Y102019D01*
Y101603D01*
X659546Y101394D01*
G01Y107019D02*
X659236Y107228D01*
Y107644D01*
X659546Y107853D01*
X659856Y107644D01*
Y107228D01*
X659546Y107019D01*
G01X668846Y101811D02*
Y114311D01*
X672721D01*
X673961Y113686D01*
X674736Y112853D01*
X675046Y111186D01*
X674736Y109519D01*
X673806Y108478D01*
X672721Y107853D01*
X668846D01*
G01X672721D02*
X675046Y101811D01*
G01X682021Y107436D02*
X686981D01*
X686516Y108894D01*
X685741Y109728D01*
X684656Y110144D01*
X683571Y109936D01*
X682641Y109311D01*
X682021Y107853D01*
X681711Y106602D01*
Y105353D01*
X682021Y104103D01*
X682796Y102852D01*
X683726Y102019D01*
X684811Y101811D01*
X685896Y102228D01*
X686981Y103477D01*
G01X695816Y101811D02*
Y112436D01*
X696126Y113477D01*
X696746Y114103D01*
X697676Y114311D01*
X698606Y113894D01*
X699071Y112853D01*
G01X697211Y109311D02*
X694111D01*
G01X706821Y107436D02*
X711781D01*
X711316Y108894D01*
X710541Y109728D01*
X709456Y110144D01*
X708371Y109936D01*
X707441Y109311D01*
X706821Y107853D01*
X706511Y106602D01*
Y105353D01*
X706821Y104103D01*
X707596Y102852D01*
X708526Y102019D01*
X709611Y101811D01*
X710696Y102228D01*
X711781Y103477D01*
G01X719376Y101811D02*
Y110144D01*
G01Y108478D02*
X720151Y109311D01*
X720926Y109936D01*
X722011Y110144D01*
X722786Y109936D01*
X723716Y109311D01*
G01X746346Y114311D02*
Y101811D01*
G01X744176Y110144D02*
X748516D01*
G01X758746Y101811D02*
X757816Y102019D01*
X756886Y102852D01*
X756266Y104311D01*
X755956Y105978D01*
X756266Y107644D01*
X756886Y109103D01*
X757816Y109936D01*
X758746Y110144D01*
X759676Y109936D01*
X760606Y109103D01*
X761226Y107644D01*
X761381Y105978D01*
X761226Y104311D01*
X760606Y102852D01*
X759676Y102019D01*
X758746Y101811D01*
G01X780136D02*
Y114311D01*
X783236D01*
X784476Y113686D01*
X785406Y112853D01*
X786181Y111603D01*
X786801Y110144D01*
X786956Y108061D01*
X786801Y105978D01*
X786181Y104519D01*
X785406Y103269D01*
X784476Y102436D01*
X783236Y101811D01*
X780136D01*
G01X792846D02*
Y114311D01*
X796721D01*
X797961Y113686D01*
X798736Y112853D01*
X799046Y111186D01*
X798736Y109519D01*
X797806Y108478D01*
X796721Y107853D01*
X792846D01*
G01X796721D02*
X799046Y101811D01*
G01X806486Y114311D02*
X810206D01*
G01X808346D02*
Y101811D01*
G01X806486D02*
X810206D01*
G01X817646Y114311D02*
Y101811D01*
X823846D01*
G01X830046Y114311D02*
Y101811D01*
X836246D01*
G01X857946D02*
Y114311D01*
G01X873136Y101811D02*
Y110144D01*
G01Y108686D02*
X872516Y109519D01*
X871586Y109936D01*
X870501Y110144D01*
X869416Y109728D01*
X868486Y108894D01*
X867866Y107644D01*
X867556Y105978D01*
X867866Y104311D01*
X868486Y103061D01*
X869416Y102228D01*
X870501Y101811D01*
X871586Y102019D01*
X872516Y102644D01*
X873136Y103477D01*
G01X879491Y98061D02*
X880421Y97644D01*
X881661Y98061D01*
X882436Y98894D01*
X883056Y99936D01*
X883986Y103269D01*
X886001Y110144D01*
G01X881041D02*
X883986Y103269D01*
G01X892821Y107436D02*
X897781D01*
X897316Y108894D01*
X896541Y109728D01*
X895456Y110144D01*
X894371Y109936D01*
X893441Y109311D01*
X892821Y107853D01*
X892511Y106602D01*
Y105353D01*
X892821Y104103D01*
X893596Y102852D01*
X894526Y102019D01*
X895611Y101811D01*
X896696Y102228D01*
X897781Y103477D01*
G01X905376Y101811D02*
Y110144D01*
G01Y108478D02*
X906151Y109311D01*
X906926Y109936D01*
X908011Y110144D01*
X908786Y109936D01*
X909716Y109311D01*
G01X931416Y101811D02*
Y112436D01*
X931726Y113477D01*
X932346Y114103D01*
X933276Y114311D01*
X934206Y113894D01*
X934671Y112853D01*
G01X932811Y109311D02*
X929711D01*
G01X944746Y101811D02*
X943816Y102019D01*
X942886Y102852D01*
X942266Y104311D01*
X941956Y105978D01*
X942266Y107644D01*
X942886Y109103D01*
X943816Y109936D01*
X944746Y110144D01*
X945676Y109936D01*
X946606Y109103D01*
X947226Y107644D01*
X947381Y105978D01*
X947226Y104311D01*
X946606Y102852D01*
X945676Y102019D01*
X944746Y101811D01*
G01X954976D02*
Y110144D01*
G01Y108478D02*
X955751Y109311D01*
X956526Y109936D01*
X957611Y110144D01*
X958386Y109936D01*
X959316Y109311D01*
G01X985046Y101811D02*
X978846D01*
Y114311D01*
X985046D01*
G01X982566Y108269D02*
X978846D01*
G01X991246Y114311D02*
Y101811D01*
X997446D01*
G01X1003646Y114311D02*
Y101811D01*
X1009846D01*
G01X1017286Y114311D02*
X1021006D01*
G01X1019146D02*
Y101811D01*
G01X1017286D02*
X1021006D01*
G01X1028446D02*
Y114311D01*
X1032166D01*
X1033406Y113686D01*
X1034336Y112228D01*
X1034646Y110561D01*
X1034336Y108894D01*
X1033561Y107644D01*
X1032166Y107019D01*
X1028446D01*
G01X1040691Y103477D02*
X1041931Y102436D01*
X1043326Y101811D01*
X1044566D01*
X1045806Y102436D01*
X1046736Y103477D01*
X1047201Y104936D01*
X1046891Y106394D01*
X1046116Y107644D01*
X1044721Y108478D01*
X1042861Y108894D01*
X1041776Y109728D01*
X1041311Y111186D01*
X1041621Y112644D01*
X1042396Y113686D01*
X1043481Y114311D01*
X1044566D01*
X1045651Y113894D01*
X1046581Y112853D01*
G01X1059446Y101811D02*
X1053246D01*
Y114311D01*
X1059446D01*
G01X1056966Y108269D02*
X1053246D01*
G01X1083936Y114311D02*
Y101811D01*
G01Y103686D02*
X1083316Y102644D01*
X1082386Y102019D01*
X1081301Y101811D01*
X1080061Y102228D01*
X1079131Y103269D01*
X1078511Y104519D01*
X1078356Y105978D01*
X1078511Y107436D01*
X1079131Y108686D01*
X1080061Y109728D01*
X1081301Y110144D01*
X1082386Y109936D01*
X1083161Y109519D01*
X1083936Y108686D01*
G01X1091376Y101811D02*
Y110144D01*
G01Y108478D02*
X1092151Y109311D01*
X1092926Y109936D01*
X1094011Y110144D01*
X1094786Y109936D01*
X1095716Y109311D01*
G01X1105946Y110144D02*
Y101811D01*
G01Y113477D02*
X1105636Y113686D01*
Y114103D01*
X1105946Y114311D01*
X1106256Y114103D01*
Y113686D01*
X1105946Y113477D01*
G01X1118346Y101811D02*
Y114311D01*
G01X1130746Y101811D02*
Y114311D01*
G01X1158336D02*
Y101811D01*
G01Y103686D02*
X1157716Y102644D01*
X1156786Y102019D01*
X1155701Y101811D01*
X1154461Y102228D01*
X1153531Y103269D01*
X1152911Y104519D01*
X1152756Y105978D01*
X1152911Y107436D01*
X1153531Y108686D01*
X1154461Y109728D01*
X1155701Y110144D01*
X1156786Y109936D01*
X1157561Y109519D01*
X1158336Y108686D01*
G01X1167946Y110144D02*
Y101811D01*
G01Y113477D02*
X1167636Y113686D01*
Y114103D01*
X1167946Y114311D01*
X1168256Y114103D01*
Y113686D01*
X1167946Y113477D01*
G01X1178176Y101811D02*
Y110144D01*
G01Y108478D02*
X1178951Y109311D01*
X1179726Y109936D01*
X1180811Y110144D01*
X1181586Y109936D01*
X1182516Y109311D01*
G01X1190421Y107436D02*
X1195381D01*
X1194916Y108894D01*
X1194141Y109728D01*
X1193056Y110144D01*
X1191971Y109936D01*
X1191041Y109311D01*
X1190421Y107853D01*
X1190111Y106602D01*
Y105353D01*
X1190421Y104103D01*
X1191196Y102852D01*
X1192126Y102019D01*
X1193211Y101811D01*
X1194296Y102228D01*
X1195381Y103477D01*
G01X1207626Y109103D02*
X1206541Y109936D01*
X1205611Y110144D01*
X1204371Y109728D01*
X1203441Y108894D01*
X1202821Y107436D01*
X1202666Y105978D01*
X1202821Y104519D01*
X1203441Y103269D01*
X1204371Y102228D01*
X1205611Y101811D01*
X1206696Y102228D01*
X1207626Y103061D01*
G01X1217546Y114311D02*
Y101811D01*
G01X1215376Y110144D02*
X1219716D01*
G01X1229946D02*
Y101811D01*
G01Y113477D02*
X1229636Y113686D01*
Y114103D01*
X1229946Y114311D01*
X1230256Y114103D01*
Y113686D01*
X1229946Y113477D01*
G01X1242346Y101811D02*
X1241416Y102019D01*
X1240486Y102852D01*
X1239866Y104311D01*
X1239556Y105978D01*
X1239866Y107644D01*
X1240486Y109103D01*
X1241416Y109936D01*
X1242346Y110144D01*
X1243276Y109936D01*
X1244206Y109103D01*
X1244826Y107644D01*
X1244981Y105978D01*
X1244826Y104311D01*
X1244206Y102852D01*
X1243276Y102019D01*
X1242346Y101811D01*
G01X1252111D02*
Y110144D01*
G01Y108061D02*
X1252731Y109103D01*
X1253661Y109936D01*
X1254901Y110144D01*
X1255986Y109936D01*
X1256916Y109103D01*
X1257381Y107644D01*
Y101811D01*
G01X605296Y131811D02*
Y494011D01*
X1088896D01*
Y131811D01*
X605296D01*
G01Y216111D02*
X1088896D01*
G01X605296Y188011D02*
X1088896D01*
G01X605296Y159911D02*
X1088896D01*
G01X605296Y272311D02*
X1088896D01*
G01X605296Y244211D02*
X1088896D01*
G01X605296Y356611D02*
X1088896D01*
G01X605296Y328511D02*
X1088896D01*
G01X605296Y300411D02*
X1088896D01*
G01X616301Y422161D02*
Y434661D01*
X622191D01*
G01X620021Y428619D02*
X616301D01*
G01X629786Y434661D02*
X633506D01*
G01X631646D02*
Y422161D01*
G01X629786D02*
X633506D01*
G01X644976Y428411D02*
X648076D01*
Y424661D01*
X647146Y423411D01*
X646061Y422578D01*
X644511Y422161D01*
X642961Y422578D01*
X641876Y423411D01*
X640946Y424661D01*
X640326Y426119D01*
X640016Y427786D01*
Y429244D01*
X640326Y430494D01*
X640946Y431953D01*
X641876Y433203D01*
X642806Y434036D01*
X644046Y434661D01*
X645131D01*
X646371Y434244D01*
X647301Y433411D01*
G01X653036Y434661D02*
Y425703D01*
X653656Y423827D01*
X654896Y422578D01*
X656446Y422161D01*
X657996Y422578D01*
X659236Y423827D01*
X659856Y425703D01*
Y434661D01*
G01X665746Y422161D02*
Y434661D01*
X669621D01*
X670861Y434036D01*
X671636Y433203D01*
X671946Y431536D01*
X671636Y429869D01*
X670706Y428828D01*
X669621Y428203D01*
X665746D01*
G01X669621D02*
X671946Y422161D01*
G01X684346D02*
X678146D01*
Y434661D01*
X684346D01*
G01X681866Y428619D02*
X678146D01*
G01X605296Y440911D02*
X1088896D01*
G01X605296Y412811D02*
X1088896D01*
G01X605296Y384711D02*
X1088896D01*
G01X605296Y469011D02*
X1088896D01*
G01X695196Y440911D02*
Y131811D01*
G01X719221Y450261D02*
X723096Y462761D01*
X726971Y450261D01*
G01X725576Y454636D02*
X720616D01*
G01X732396Y462761D02*
Y450261D01*
X738596D01*
G01X744796Y462761D02*
Y450261D01*
X750996D01*
G01X769286Y462761D02*
Y453803D01*
X769906Y451927D01*
X771146Y450678D01*
X772696Y450261D01*
X774246Y450678D01*
X775486Y451927D01*
X776106Y453803D01*
Y462761D01*
G01X781531Y450261D02*
Y462761D01*
X788661Y450261D01*
Y462761D01*
G01X795636D02*
X799356D01*
G01X797496D02*
Y450261D01*
G01X795636D02*
X799356D01*
G01X809896Y462761D02*
Y450261D01*
G01X806331Y462761D02*
X813461D01*
G01X819041Y451927D02*
X820281Y450886D01*
X821676Y450261D01*
X822916D01*
X824156Y450886D01*
X825086Y451927D01*
X825551Y453386D01*
X825241Y454844D01*
X824466Y456094D01*
X823071Y456928D01*
X821211Y457344D01*
X820126Y458178D01*
X819661Y459636D01*
X819971Y461094D01*
X820746Y462136D01*
X821831Y462761D01*
X822916D01*
X824001Y462344D01*
X824931Y461303D01*
G01X843221Y450261D02*
X847096Y462761D01*
X850971Y450261D01*
G01X849576Y454636D02*
X844616D01*
G01X856396Y450261D02*
Y462761D01*
X860271D01*
X861511Y462136D01*
X862286Y461303D01*
X862596Y459636D01*
X862286Y457969D01*
X861356Y456928D01*
X860271Y456303D01*
X856396D01*
G01X860271D02*
X862596Y450261D01*
G01X874996D02*
X868796D01*
Y462761D01*
X874996D01*
G01X872516Y456719D02*
X868796D01*
G01X894836Y462761D02*
X898556D01*
G01X896696D02*
Y450261D01*
G01X894836D02*
X898556D01*
G01X905531D02*
Y462761D01*
X912661Y450261D01*
Y462761D01*
G01X929866Y450261D02*
Y462761D01*
X933896Y452344D01*
X937926Y462761D01*
Y450261D01*
G01X944436Y462761D02*
X948156D01*
G01X946296D02*
Y450261D01*
G01X944436D02*
X948156D01*
G01X955596Y462761D02*
Y450261D01*
X961796D01*
G01X967841Y451927D02*
X969081Y450886D01*
X970476Y450261D01*
X971716D01*
X972956Y450886D01*
X973886Y451927D01*
X974351Y453386D01*
X974041Y454844D01*
X973266Y456094D01*
X971871Y456928D01*
X970011Y457344D01*
X968926Y458178D01*
X968461Y459636D01*
X968771Y461094D01*
X969546Y462136D01*
X970631Y462761D01*
X971716D01*
X972801Y462344D01*
X973731Y461303D01*
G01X688686Y475261D02*
Y487761D01*
X691786D01*
X693026Y487136D01*
X693956Y486303D01*
X694731Y485053D01*
X695351Y483594D01*
X695506Y481511D01*
X695351Y479428D01*
X694731Y477969D01*
X693956Y476719D01*
X693026Y475886D01*
X691786Y475261D01*
X688686D01*
G01X701396D02*
Y487761D01*
X705271D01*
X706511Y487136D01*
X707286Y486303D01*
X707596Y484636D01*
X707286Y482969D01*
X706356Y481928D01*
X705271Y481303D01*
X701396D01*
G01X705271D02*
X707596Y475261D01*
G01X715036Y487761D02*
X718756D01*
G01X716896D02*
Y475261D01*
G01X715036D02*
X718756D01*
G01X726196Y487761D02*
Y475261D01*
X732396D01*
G01X738596Y487761D02*
Y475261D01*
X744796D01*
G01X769906Y486719D02*
X768976Y487344D01*
X767891Y487761D01*
X766651D01*
X765256Y487136D01*
X764171Y486094D01*
X763396Y484844D01*
X762776Y482761D01*
X762621Y480886D01*
X762931Y479011D01*
X763396Y477761D01*
X764326Y476511D01*
X765411Y475678D01*
X766496Y475261D01*
X767581D01*
X768666Y475678D01*
X769596Y476302D01*
X770371Y477136D01*
G01X775641Y475261D02*
Y487761D01*
G01X782151D02*
Y475261D01*
G01Y481511D02*
X775641D01*
G01X787421Y475261D02*
X791296Y487761D01*
X795171Y475261D01*
G01X793776Y479636D02*
X788816D01*
G01X800596Y475261D02*
Y487761D01*
X804471D01*
X805711Y487136D01*
X806486Y486303D01*
X806796Y484636D01*
X806486Y482969D01*
X805556Y481928D01*
X804471Y481303D01*
X800596D01*
G01X804471D02*
X806796Y475261D01*
G01X816096Y487761D02*
Y475261D01*
G01X812531Y487761D02*
X819661D01*
G01X828496Y474844D02*
X828186Y475053D01*
Y475469D01*
X828496Y475678D01*
X828806Y475469D01*
Y475053D01*
X828496Y474844D01*
G01Y480469D02*
X828186Y480678D01*
Y481094D01*
X828496Y481303D01*
X828806Y481094D01*
Y480678D01*
X828496Y480469D01*
G01X853296Y487761D02*
Y475261D01*
G01X849731Y487761D02*
X856861D01*
G01X865696Y475261D02*
X864456Y475469D01*
X863371Y476302D01*
X862441Y477553D01*
X861821Y479011D01*
X861511Y480678D01*
Y482344D01*
X861821Y484011D01*
X862441Y485469D01*
X863371Y486719D01*
X864456Y487553D01*
X865696Y487761D01*
X866936Y487553D01*
X868021Y486719D01*
X868951Y485469D01*
X869571Y484011D01*
X869881Y482344D01*
Y480678D01*
X869571Y479011D01*
X868951Y477553D01*
X868021Y476302D01*
X866936Y475469D01*
X865696Y475261D01*
G01X874996D02*
Y487761D01*
X878716D01*
X879956Y487136D01*
X880886Y485678D01*
X881196Y484011D01*
X880886Y482344D01*
X880111Y481094D01*
X878716Y480469D01*
X874996D01*
G01X902896Y487761D02*
Y475261D01*
G01X900726Y483594D02*
X905066D01*
G01X915296Y475261D02*
X914366Y475469D01*
X913436Y476302D01*
X912816Y477761D01*
X912506Y479428D01*
X912816Y481094D01*
X913436Y482553D01*
X914366Y483386D01*
X915296Y483594D01*
X916226Y483386D01*
X917156Y482553D01*
X917776Y481094D01*
X917931Y479428D01*
X917776Y477761D01*
X917156Y476302D01*
X916226Y475469D01*
X915296Y475261D01*
G01X941336Y481928D02*
X941956Y482553D01*
X942421Y483594D01*
X942731Y485053D01*
X942421Y486303D01*
X941801Y487136D01*
X940716Y487761D01*
X936531D01*
Y475261D01*
X941646D01*
X942731Y476094D01*
X943351Y477344D01*
X943661Y478803D01*
X943351Y480261D01*
X942421Y481511D01*
X941336Y481928D01*
X936531D01*
G01X952496Y475261D02*
X951256Y475469D01*
X950171Y476302D01*
X949241Y477553D01*
X948621Y479011D01*
X948311Y480678D01*
Y482344D01*
X948621Y484011D01*
X949241Y485469D01*
X950171Y486719D01*
X951256Y487553D01*
X952496Y487761D01*
X953736Y487553D01*
X954821Y486719D01*
X955751Y485469D01*
X956371Y484011D01*
X956681Y482344D01*
Y480678D01*
X956371Y479011D01*
X955751Y477553D01*
X954821Y476302D01*
X953736Y475469D01*
X952496Y475261D01*
G01X964896Y487761D02*
Y475261D01*
G01X961331Y487761D02*
X968461D01*
G01X977296D02*
Y475261D01*
G01X973731Y487761D02*
X980861D01*
G01X989696Y475261D02*
X988456Y475469D01*
X987371Y476302D01*
X986441Y477553D01*
X985821Y479011D01*
X985511Y480678D01*
Y482344D01*
X985821Y484011D01*
X986441Y485469D01*
X987371Y486719D01*
X988456Y487553D01*
X989696Y487761D01*
X990936Y487553D01*
X992021Y486719D01*
X992951Y485469D01*
X993571Y484011D01*
X993881Y482344D01*
Y480678D01*
X993571Y479011D01*
X992951Y477553D01*
X992021Y476302D01*
X990936Y475469D01*
X989696Y475261D01*
G01X998066D02*
Y487761D01*
X1002096Y477344D01*
X1006126Y487761D01*
Y475261D01*
G01X821166Y-397333D02*
X819419Y-397916D01*
X818109Y-399375D01*
X817236Y-401124D01*
X816581Y-403458D01*
X816363Y-406083D01*
X816581Y-408708D01*
X817236Y-411042D01*
X818109Y-412792D01*
X819419Y-414250D01*
X821166Y-414833D01*
X822912Y-414250D01*
X824223Y-412792D01*
X825096Y-411042D01*
X825751Y-408708D01*
X825969Y-406083D01*
X825751Y-403458D01*
X825096Y-401124D01*
X824223Y-399375D01*
X822912Y-397916D01*
X821166Y-397333D01*
G01X833863Y-411333D02*
X835172Y-413375D01*
X836919Y-414541D01*
X838884Y-414833D01*
X840631Y-414541D01*
X842378Y-413083D01*
X843469Y-411333D01*
X843688Y-409583D01*
X843251Y-407542D01*
X841723Y-406083D01*
X840194Y-405500D01*
X838229D01*
G01X840194D02*
X841504Y-404625D01*
X842596Y-403167D01*
X843033Y-401417D01*
X842596Y-399666D01*
X841504Y-398208D01*
X839539Y-397333D01*
X837574Y-397625D01*
X835609Y-398792D01*
G01X852236Y-415416D02*
X860096Y-397333D01*
G01X869518Y-400250D02*
X870828Y-398500D01*
X872356Y-397625D01*
X874103Y-397333D01*
X876286Y-397916D01*
X877814Y-399375D01*
X878251Y-401124D01*
X878033Y-402875D01*
X877159Y-404333D01*
X872793Y-407250D01*
X870828Y-409291D01*
X869518Y-412209D01*
X869081Y-414833D01*
X878251D01*
G01X887454Y-412792D02*
X888983Y-414250D01*
X890729Y-414833D01*
X892476Y-414250D01*
X894004Y-412500D01*
X895096Y-409875D01*
X895533Y-407250D01*
Y-404042D01*
X895096Y-401417D01*
X894004Y-399083D01*
X892694Y-397916D01*
X891166Y-397333D01*
X889419Y-397916D01*
X888109Y-399083D01*
X887236Y-400833D01*
X886799Y-403167D01*
X887236Y-405208D01*
X888328Y-407250D01*
X889638Y-408417D01*
X891166Y-408708D01*
X892912Y-408125D01*
X894223Y-406666D01*
X895533Y-404042D01*
G01X904736Y-415416D02*
X912596Y-397333D01*
G01X922018Y-400250D02*
X923328Y-398500D01*
X924856Y-397625D01*
X926603Y-397333D01*
X928786Y-397916D01*
X930314Y-399375D01*
X930751Y-401124D01*
X930533Y-402875D01*
X929659Y-404333D01*
X925293Y-407250D01*
X923328Y-409291D01*
X922018Y-412209D01*
X921581Y-414833D01*
X930751D01*
G01X943666Y-397333D02*
X941919Y-397916D01*
X940609Y-399375D01*
X939736Y-401124D01*
X939081Y-403458D01*
X938863Y-406083D01*
X939081Y-408708D01*
X939736Y-411042D01*
X940609Y-412792D01*
X941919Y-414250D01*
X943666Y-414833D01*
X945412Y-414250D01*
X946723Y-412792D01*
X947596Y-411042D01*
X948251Y-408708D01*
X948469Y-406083D01*
X948251Y-403458D01*
X947596Y-401124D01*
X946723Y-399375D01*
X945412Y-397916D01*
X943666Y-397333D01*
G01X961166Y-414833D02*
Y-397333D01*
X958546Y-400833D01*
G01Y-414833D02*
X963786D01*
G01X978229D02*
X978666Y-411042D01*
X979321Y-407833D01*
X980194Y-404916D01*
X981286Y-401708D01*
X983033Y-397333D01*
X974299D01*
G01X771146Y139611D02*
X772231Y139819D01*
X773471Y140444D01*
X774246Y141486D01*
X774556Y142944D01*
X774246Y144402D01*
X773316Y145653D01*
X771921Y146278D01*
X770371D01*
X769441Y146694D01*
X768666Y147736D01*
X768356Y149194D01*
X768821Y150653D01*
X769906Y151694D01*
X771146Y152111D01*
X772386Y151694D01*
X773471Y150653D01*
X773936Y149194D01*
X773626Y147736D01*
X772851Y146694D01*
X771921Y146278D01*
X770371D01*
X768976Y145653D01*
X768046Y144402D01*
X767736Y142944D01*
X768046Y141486D01*
X768821Y140444D01*
X770061Y139819D01*
X771146Y139611D01*
G01X780601Y144819D02*
X781686Y146278D01*
X782616Y147111D01*
X783856Y147528D01*
X784941Y147111D01*
X785716Y146278D01*
X786336Y145028D01*
X786491Y143569D01*
X786336Y142319D01*
X785716Y141069D01*
X784786Y140028D01*
X783701Y139611D01*
X782461Y140028D01*
X781376Y141277D01*
X780756Y143153D01*
X780601Y145236D01*
X780911Y147944D01*
X781376Y149403D01*
X782151Y150861D01*
X783236Y151903D01*
X784321Y152111D01*
X785406Y151694D01*
X786181Y150653D01*
G01X795946Y139194D02*
X795636Y139403D01*
Y139819D01*
X795946Y140028D01*
X796256Y139819D01*
Y139403D01*
X795946Y139194D01*
G01X808346Y152111D02*
X807106Y151694D01*
X806176Y150653D01*
X805556Y149403D01*
X805091Y147736D01*
X804936Y145861D01*
X805091Y143986D01*
X805556Y142319D01*
X806176Y141069D01*
X807106Y140028D01*
X808346Y139611D01*
X809586Y140028D01*
X810516Y141069D01*
X811136Y142319D01*
X811601Y143986D01*
X811756Y145861D01*
X811601Y147736D01*
X811136Y149403D01*
X810516Y150653D01*
X809586Y151694D01*
X808346Y152111D01*
G01X768511Y225369D02*
X769596Y224328D01*
X770836Y223911D01*
X772076Y224328D01*
X773161Y225577D01*
X773936Y227453D01*
X774246Y229328D01*
Y231619D01*
X773936Y233494D01*
X773161Y235161D01*
X772231Y235994D01*
X771146Y236411D01*
X769906Y235994D01*
X768976Y235161D01*
X768356Y233911D01*
X768046Y232244D01*
X768356Y230786D01*
X769131Y229328D01*
X770061Y228494D01*
X771146Y228286D01*
X772386Y228702D01*
X773316Y229744D01*
X774246Y231619D01*
G01X783546Y223911D02*
Y236411D01*
X781686Y233911D01*
G01Y223911D02*
X785406D01*
G01X795946Y223494D02*
X795636Y223703D01*
Y224119D01*
X795946Y224328D01*
X796256Y224119D01*
Y223703D01*
X795946Y223494D01*
G01X808346Y236411D02*
X807106Y235994D01*
X806176Y234953D01*
X805556Y233703D01*
X805091Y232036D01*
X804936Y230161D01*
X805091Y228286D01*
X805556Y226619D01*
X806176Y225369D01*
X807106Y224328D01*
X808346Y223911D01*
X809586Y224328D01*
X810516Y225369D01*
X811136Y226619D01*
X811601Y228286D01*
X811756Y230161D01*
X811601Y232036D01*
X811136Y233703D01*
X810516Y234953D01*
X809586Y235994D01*
X808346Y236411D01*
G01X762001Y206228D02*
X762931Y207477D01*
X764016Y208103D01*
X765256Y208311D01*
X766806Y207894D01*
X767891Y206853D01*
X768201Y205603D01*
X768046Y204352D01*
X767426Y203311D01*
X764326Y201228D01*
X762931Y199769D01*
X762001Y197686D01*
X761691Y195811D01*
X768201D01*
G01X774401Y206228D02*
X775331Y207477D01*
X776416Y208103D01*
X777656Y208311D01*
X779206Y207894D01*
X780291Y206853D01*
X780601Y205603D01*
X780446Y204352D01*
X779826Y203311D01*
X776726Y201228D01*
X775331Y199769D01*
X774401Y197686D01*
X774091Y195811D01*
X780601D01*
G01X791606D02*
Y208311D01*
X785871Y199353D01*
X793621D01*
G01X802146Y195394D02*
X801836Y195603D01*
Y196019D01*
X802146Y196228D01*
X802456Y196019D01*
Y195603D01*
X802146Y195394D01*
G01X814546Y208311D02*
X813306Y207894D01*
X812376Y206853D01*
X811756Y205603D01*
X811291Y203936D01*
X811136Y202061D01*
X811291Y200186D01*
X811756Y198519D01*
X812376Y197269D01*
X813306Y196228D01*
X814546Y195811D01*
X815786Y196228D01*
X816716Y197269D01*
X817336Y198519D01*
X817801Y200186D01*
X817956Y202061D01*
X817801Y203936D01*
X817336Y205603D01*
X816716Y206853D01*
X815786Y207894D01*
X814546Y208311D01*
G01X767736Y169586D02*
X768666Y168544D01*
X769751Y167919D01*
X771146Y167711D01*
X772541Y168128D01*
X773626Y168961D01*
X774401Y170419D01*
X774556Y172086D01*
X774246Y173753D01*
X773471Y174794D01*
X772386Y175628D01*
X771301Y175836D01*
X770216Y175628D01*
X768821Y174794D01*
X769286Y180211D01*
X773471D01*
G01X780601Y178128D02*
X781531Y179377D01*
X782616Y180003D01*
X783856Y180211D01*
X785406Y179794D01*
X786491Y178753D01*
X786801Y177503D01*
X786646Y176252D01*
X786026Y175211D01*
X782926Y173128D01*
X781531Y171669D01*
X780601Y169586D01*
X780291Y167711D01*
X786801D01*
G01X795946Y167294D02*
X795636Y167503D01*
Y167919D01*
X795946Y168128D01*
X796256Y167919D01*
Y167503D01*
X795946Y167294D01*
G01X808346Y180211D02*
X807106Y179794D01*
X806176Y178753D01*
X805556Y177503D01*
X805091Y175836D01*
X804936Y173961D01*
X805091Y172086D01*
X805556Y170419D01*
X806176Y169169D01*
X807106Y168128D01*
X808346Y167711D01*
X809586Y168128D01*
X810516Y169169D01*
X811136Y170419D01*
X811601Y172086D01*
X811756Y173961D01*
X811601Y175836D01*
X811136Y177503D01*
X810516Y178753D01*
X809586Y179794D01*
X808346Y180211D01*
G01X767736Y282611D02*
X768666Y281152D01*
X769906Y280319D01*
X771301Y280111D01*
X772541Y280319D01*
X773781Y281361D01*
X774556Y282611D01*
X774711Y283861D01*
X774401Y285319D01*
X773316Y286361D01*
X772231Y286778D01*
X770836D01*
G01X772231D02*
X773161Y287403D01*
X773936Y288444D01*
X774246Y289694D01*
X773936Y290944D01*
X773161Y291986D01*
X771766Y292611D01*
X770371Y292403D01*
X768976Y291569D01*
G01X780601Y290528D02*
X781531Y291777D01*
X782616Y292403D01*
X783856Y292611D01*
X785406Y292194D01*
X786491Y291153D01*
X786801Y289903D01*
X786646Y288652D01*
X786026Y287611D01*
X782926Y285528D01*
X781531Y284069D01*
X780601Y281986D01*
X780291Y280111D01*
X786801D01*
G01X795946Y279694D02*
X795636Y279903D01*
Y280319D01*
X795946Y280528D01*
X796256Y280319D01*
Y279903D01*
X795946Y279694D01*
G01X808346Y292611D02*
X807106Y292194D01*
X806176Y291153D01*
X805556Y289903D01*
X805091Y288236D01*
X804936Y286361D01*
X805091Y284486D01*
X805556Y282819D01*
X806176Y281569D01*
X807106Y280528D01*
X808346Y280111D01*
X809586Y280528D01*
X810516Y281569D01*
X811136Y282819D01*
X811601Y284486D01*
X811756Y286361D01*
X811601Y288236D01*
X811136Y289903D01*
X810516Y291153D01*
X809586Y292194D01*
X808346Y292611D01*
G01X767736Y254511D02*
X768666Y253052D01*
X769906Y252219D01*
X771301Y252011D01*
X772541Y252219D01*
X773781Y253261D01*
X774556Y254511D01*
X774711Y255761D01*
X774401Y257219D01*
X773316Y258261D01*
X772231Y258678D01*
X770836D01*
G01X772231D02*
X773161Y259303D01*
X773936Y260344D01*
X774246Y261594D01*
X773936Y262844D01*
X773161Y263886D01*
X771766Y264511D01*
X770371Y264303D01*
X768976Y263469D01*
G01X780601Y257219D02*
X781686Y258678D01*
X782616Y259511D01*
X783856Y259928D01*
X784941Y259511D01*
X785716Y258678D01*
X786336Y257428D01*
X786491Y255969D01*
X786336Y254719D01*
X785716Y253469D01*
X784786Y252428D01*
X783701Y252011D01*
X782461Y252428D01*
X781376Y253677D01*
X780756Y255553D01*
X780601Y257636D01*
X780911Y260344D01*
X781376Y261803D01*
X782151Y263261D01*
X783236Y264303D01*
X784321Y264511D01*
X785406Y264094D01*
X786181Y263053D01*
G01X795946Y251594D02*
X795636Y251803D01*
Y252219D01*
X795946Y252428D01*
X796256Y252219D01*
Y251803D01*
X795946Y251594D01*
G01X808346Y264511D02*
X807106Y264094D01*
X806176Y263053D01*
X805556Y261803D01*
X805091Y260136D01*
X804936Y258261D01*
X805091Y256386D01*
X805556Y254719D01*
X806176Y253469D01*
X807106Y252428D01*
X808346Y252011D01*
X809586Y252428D01*
X810516Y253469D01*
X811136Y254719D01*
X811601Y256386D01*
X811756Y258261D01*
X811601Y260136D01*
X811136Y261803D01*
X810516Y263053D01*
X809586Y264094D01*
X808346Y264511D01*
G01X771146Y364411D02*
Y376911D01*
X769286Y374411D01*
G01Y364411D02*
X773006D01*
G01X780601Y374828D02*
X781531Y376077D01*
X782616Y376703D01*
X783856Y376911D01*
X785406Y376494D01*
X786491Y375453D01*
X786801Y374203D01*
X786646Y372952D01*
X786026Y371911D01*
X782926Y369828D01*
X781531Y368369D01*
X780601Y366286D01*
X780291Y364411D01*
X786801D01*
G01X795946Y363994D02*
X795636Y364203D01*
Y364619D01*
X795946Y364828D01*
X796256Y364619D01*
Y364203D01*
X795946Y363994D01*
G01X808346Y376911D02*
X807106Y376494D01*
X806176Y375453D01*
X805556Y374203D01*
X805091Y372536D01*
X804936Y370661D01*
X805091Y368786D01*
X805556Y367119D01*
X806176Y365869D01*
X807106Y364828D01*
X808346Y364411D01*
X809586Y364828D01*
X810516Y365869D01*
X811136Y367119D01*
X811601Y368786D01*
X811756Y370661D01*
X811601Y372536D01*
X811136Y374203D01*
X810516Y375453D01*
X809586Y376494D01*
X808346Y376911D01*
G01X771146Y336311D02*
Y348811D01*
X769286Y346311D01*
G01Y336311D02*
X773006D01*
G01X780601Y341519D02*
X781686Y342978D01*
X782616Y343811D01*
X783856Y344228D01*
X784941Y343811D01*
X785716Y342978D01*
X786336Y341728D01*
X786491Y340269D01*
X786336Y339019D01*
X785716Y337769D01*
X784786Y336728D01*
X783701Y336311D01*
X782461Y336728D01*
X781376Y337977D01*
X780756Y339853D01*
X780601Y341936D01*
X780911Y344644D01*
X781376Y346103D01*
X782151Y347561D01*
X783236Y348603D01*
X784321Y348811D01*
X785406Y348394D01*
X786181Y347353D01*
G01X795946Y335894D02*
X795636Y336103D01*
Y336519D01*
X795946Y336728D01*
X796256Y336519D01*
Y336103D01*
X795946Y335894D01*
G01X808346Y348811D02*
X807106Y348394D01*
X806176Y347353D01*
X805556Y346103D01*
X805091Y344436D01*
X804936Y342561D01*
X805091Y340686D01*
X805556Y339019D01*
X806176Y337769D01*
X807106Y336728D01*
X808346Y336311D01*
X809586Y336728D01*
X810516Y337769D01*
X811136Y339019D01*
X811601Y340686D01*
X811756Y342561D01*
X811601Y344436D01*
X811136Y346103D01*
X810516Y347353D01*
X809586Y348394D01*
X808346Y348811D01*
G01X768201Y318628D02*
X769131Y319877D01*
X770216Y320503D01*
X771456Y320711D01*
X773006Y320294D01*
X774091Y319253D01*
X774401Y318003D01*
X774246Y316752D01*
X773626Y315711D01*
X770526Y313628D01*
X769131Y312169D01*
X768201Y310086D01*
X767891Y308211D01*
X774401D01*
G01X783546D02*
X784631Y308419D01*
X785871Y309044D01*
X786646Y310086D01*
X786956Y311544D01*
X786646Y313002D01*
X785716Y314253D01*
X784321Y314878D01*
X782771D01*
X781841Y315294D01*
X781066Y316336D01*
X780756Y317794D01*
X781221Y319253D01*
X782306Y320294D01*
X783546Y320711D01*
X784786Y320294D01*
X785871Y319253D01*
X786336Y317794D01*
X786026Y316336D01*
X785251Y315294D01*
X784321Y314878D01*
X782771D01*
X781376Y314253D01*
X780446Y313002D01*
X780136Y311544D01*
X780446Y310086D01*
X781221Y309044D01*
X782461Y308419D01*
X783546Y308211D01*
G01X795946Y307794D02*
X795636Y308003D01*
Y308419D01*
X795946Y308628D01*
X796256Y308419D01*
Y308003D01*
X795946Y307794D01*
G01X808346Y320711D02*
X807106Y320294D01*
X806176Y319253D01*
X805556Y318003D01*
X805091Y316336D01*
X804936Y314461D01*
X805091Y312586D01*
X805556Y310919D01*
X806176Y309669D01*
X807106Y308628D01*
X808346Y308211D01*
X809586Y308628D01*
X810516Y309669D01*
X811136Y310919D01*
X811601Y312586D01*
X811756Y314461D01*
X811601Y316336D01*
X811136Y318003D01*
X810516Y319253D01*
X809586Y320294D01*
X808346Y320711D01*
G01X767891Y423827D02*
X769131Y422786D01*
X770526Y422161D01*
X771766D01*
X773006Y422786D01*
X773936Y423827D01*
X774401Y425286D01*
X774091Y426744D01*
X773316Y427994D01*
X771921Y428828D01*
X770061Y429244D01*
X768976Y430078D01*
X768511Y431536D01*
X768821Y432994D01*
X769596Y434036D01*
X770681Y434661D01*
X771766D01*
X772851Y434244D01*
X773781Y433203D01*
G01X781686Y434661D02*
X785406D01*
G01X783546D02*
Y422161D01*
G01X781686D02*
X785406D01*
G01X793001Y434661D02*
X798891D01*
X793001Y422161D01*
X798891D01*
G01X811446D02*
X805246D01*
Y434661D01*
X811446D01*
G01X808966Y428619D02*
X805246D01*
G01X771146Y392511D02*
Y405011D01*
X769286Y402511D01*
G01Y392511D02*
X773006D01*
G01X783546Y405011D02*
X782306Y404594D01*
X781376Y403553D01*
X780756Y402303D01*
X780291Y400636D01*
X780136Y398761D01*
X780291Y396886D01*
X780756Y395219D01*
X781376Y393969D01*
X782306Y392928D01*
X783546Y392511D01*
X784786Y392928D01*
X785716Y393969D01*
X786336Y395219D01*
X786801Y396886D01*
X786956Y398761D01*
X786801Y400636D01*
X786336Y402303D01*
X785716Y403553D01*
X784786Y404594D01*
X783546Y405011D01*
G01X795946Y392094D02*
X795636Y392303D01*
Y392719D01*
X795946Y392928D01*
X796256Y392719D01*
Y392303D01*
X795946Y392094D01*
G01X808346Y405011D02*
X807106Y404594D01*
X806176Y403553D01*
X805556Y402303D01*
X805091Y400636D01*
X804936Y398761D01*
X805091Y396886D01*
X805556Y395219D01*
X806176Y393969D01*
X807106Y392928D01*
X808346Y392511D01*
X809586Y392928D01*
X810516Y393969D01*
X811136Y395219D01*
X811601Y396886D01*
X811756Y398761D01*
X811601Y400636D01*
X811136Y402303D01*
X810516Y403553D01*
X809586Y404594D01*
X808346Y405011D01*
G01X868863Y-369833D02*
Y-352333D01*
X873229D01*
X874976Y-353208D01*
X876286Y-354375D01*
X877378Y-356124D01*
X878251Y-358167D01*
X878469Y-361083D01*
X878251Y-364000D01*
X877378Y-366042D01*
X876286Y-367792D01*
X874976Y-368958D01*
X873229Y-369833D01*
X868863D01*
G01X895096D02*
Y-358167D01*
G01Y-360208D02*
X894223Y-359042D01*
X892912Y-358458D01*
X891384Y-358167D01*
X889856Y-358750D01*
X888546Y-359916D01*
X887672Y-361666D01*
X887236Y-364000D01*
X887672Y-366333D01*
X888546Y-368083D01*
X889856Y-369250D01*
X891384Y-369833D01*
X892912Y-369541D01*
X894223Y-368667D01*
X895096Y-367500D01*
G01X908666Y-352333D02*
Y-369833D01*
G01X905609Y-358167D02*
X911723D01*
G01X922891Y-361958D02*
X929878D01*
X929223Y-359916D01*
X928131Y-358750D01*
X926603Y-358167D01*
X925074Y-358458D01*
X923764Y-359333D01*
X922891Y-361375D01*
X922454Y-363125D01*
Y-364875D01*
X922891Y-366625D01*
X923983Y-368375D01*
X925293Y-369541D01*
X926821Y-369833D01*
X928349Y-369250D01*
X929878Y-367500D01*
G01X888481Y139611D02*
Y152111D01*
X895611Y139611D01*
Y152111D01*
G01X904446Y139611D02*
X903206Y139819D01*
X902121Y140652D01*
X901191Y141903D01*
X900571Y143361D01*
X900261Y145028D01*
Y146694D01*
X900571Y148361D01*
X901191Y149819D01*
X902121Y151069D01*
X903206Y151903D01*
X904446Y152111D01*
X905686Y151903D01*
X906771Y151069D01*
X907701Y149819D01*
X908321Y148361D01*
X908631Y146694D01*
Y145028D01*
X908321Y143361D01*
X907701Y141903D01*
X906771Y140652D01*
X905686Y139819D01*
X904446Y139611D01*
G01X913281D02*
Y152111D01*
X920411Y139611D01*
Y152111D01*
G01X927231Y143778D02*
X931261D01*
G01X938546Y139611D02*
Y152111D01*
X942266D01*
X943506Y151486D01*
X944436Y150028D01*
X944746Y148361D01*
X944436Y146694D01*
X943661Y145444D01*
X942266Y144819D01*
X938546D01*
G01X950946Y152111D02*
Y139611D01*
X957146D01*
G01X962571D02*
X966446Y152111D01*
X970321Y139611D01*
G01X968926Y143986D02*
X963966D01*
G01X978846Y152111D02*
Y139611D01*
G01X975281Y152111D02*
X982411D01*
G01X994346Y139611D02*
X988146D01*
Y152111D01*
X994346D01*
G01X991866Y146069D02*
X988146D01*
G01X1000236Y139611D02*
Y152111D01*
X1003336D01*
X1004576Y151486D01*
X1005506Y150653D01*
X1006281Y149403D01*
X1006901Y147944D01*
X1007056Y145861D01*
X1006901Y143778D01*
X1006281Y142319D01*
X1005506Y141069D01*
X1004576Y140236D01*
X1003336Y139611D01*
X1000236D01*
G01X884296Y440911D02*
Y131811D01*
G01X888481Y167711D02*
Y180211D01*
X895611Y167711D01*
Y180211D01*
G01X904446Y167711D02*
X903206Y167919D01*
X902121Y168752D01*
X901191Y170003D01*
X900571Y171461D01*
X900261Y173128D01*
Y174794D01*
X900571Y176461D01*
X901191Y177919D01*
X902121Y179169D01*
X903206Y180003D01*
X904446Y180211D01*
X905686Y180003D01*
X906771Y179169D01*
X907701Y177919D01*
X908321Y176461D01*
X908631Y174794D01*
Y173128D01*
X908321Y171461D01*
X907701Y170003D01*
X906771Y168752D01*
X905686Y167919D01*
X904446Y167711D01*
G01X913281D02*
Y180211D01*
X920411Y167711D01*
Y180211D01*
G01X927231Y171878D02*
X931261D01*
G01X938546Y167711D02*
Y180211D01*
X942266D01*
X943506Y179586D01*
X944436Y178128D01*
X944746Y176461D01*
X944436Y174794D01*
X943661Y173544D01*
X942266Y172919D01*
X938546D01*
G01X950946Y180211D02*
Y167711D01*
X957146D01*
G01X962571D02*
X966446Y180211D01*
X970321Y167711D01*
G01X968926Y172086D02*
X963966D01*
G01X978846Y180211D02*
Y167711D01*
G01X975281Y180211D02*
X982411D01*
G01X994346Y167711D02*
X988146D01*
Y180211D01*
X994346D01*
G01X991866Y174169D02*
X988146D01*
G01X1000236Y167711D02*
Y180211D01*
X1003336D01*
X1004576Y179586D01*
X1005506Y178753D01*
X1006281Y177503D01*
X1006901Y176044D01*
X1007056Y173961D01*
X1006901Y171878D01*
X1006281Y170419D01*
X1005506Y169169D01*
X1004576Y168336D01*
X1003336Y167711D01*
X1000236D01*
G01X913746Y223911D02*
Y236411D01*
X917466D01*
X918706Y235786D01*
X919636Y234328D01*
X919946Y232661D01*
X919636Y230994D01*
X918861Y229744D01*
X917466Y229119D01*
X913746D01*
G01X926146Y236411D02*
Y223911D01*
X932346D01*
G01X937771D02*
X941646Y236411D01*
X945521Y223911D01*
G01X944126Y228286D02*
X939166D01*
G01X954046Y236411D02*
Y223911D01*
G01X950481Y236411D02*
X957611D01*
G01X969546Y223911D02*
X963346D01*
Y236411D01*
X969546D01*
G01X967066Y230369D02*
X963346D01*
G01X975436Y223911D02*
Y236411D01*
X978536D01*
X979776Y235786D01*
X980706Y234953D01*
X981481Y233703D01*
X982101Y232244D01*
X982256Y230161D01*
X982101Y228078D01*
X981481Y226619D01*
X980706Y225369D01*
X979776Y224536D01*
X978536Y223911D01*
X975436D01*
G01X913746Y195811D02*
Y208311D01*
X917466D01*
X918706Y207686D01*
X919636Y206228D01*
X919946Y204561D01*
X919636Y202894D01*
X918861Y201644D01*
X917466Y201019D01*
X913746D01*
G01X926146Y208311D02*
Y195811D01*
X932346D01*
G01X937771D02*
X941646Y208311D01*
X945521Y195811D01*
G01X944126Y200186D02*
X939166D01*
G01X954046Y208311D02*
Y195811D01*
G01X950481Y208311D02*
X957611D01*
G01X969546Y195811D02*
X963346D01*
Y208311D01*
X969546D01*
G01X967066Y202269D02*
X963346D01*
G01X975436Y195811D02*
Y208311D01*
X978536D01*
X979776Y207686D01*
X980706Y206853D01*
X981481Y205603D01*
X982101Y204144D01*
X982256Y202061D01*
X982101Y199978D01*
X981481Y198519D01*
X980706Y197269D01*
X979776Y196436D01*
X978536Y195811D01*
X975436D01*
G01X913746Y280111D02*
Y292611D01*
X917466D01*
X918706Y291986D01*
X919636Y290528D01*
X919946Y288861D01*
X919636Y287194D01*
X918861Y285944D01*
X917466Y285319D01*
X913746D01*
G01X926146Y292611D02*
Y280111D01*
X932346D01*
G01X937771D02*
X941646Y292611D01*
X945521Y280111D01*
G01X944126Y284486D02*
X939166D01*
G01X954046Y292611D02*
Y280111D01*
G01X950481Y292611D02*
X957611D01*
G01X969546Y280111D02*
X963346D01*
Y292611D01*
X969546D01*
G01X967066Y286569D02*
X963346D01*
G01X975436Y280111D02*
Y292611D01*
X978536D01*
X979776Y291986D01*
X980706Y291153D01*
X981481Y289903D01*
X982101Y288444D01*
X982256Y286361D01*
X982101Y284278D01*
X981481Y282819D01*
X980706Y281569D01*
X979776Y280736D01*
X978536Y280111D01*
X975436D01*
G01X913746Y252011D02*
Y264511D01*
X917466D01*
X918706Y263886D01*
X919636Y262428D01*
X919946Y260761D01*
X919636Y259094D01*
X918861Y257844D01*
X917466Y257219D01*
X913746D01*
G01X926146Y264511D02*
Y252011D01*
X932346D01*
G01X937771D02*
X941646Y264511D01*
X945521Y252011D01*
G01X944126Y256386D02*
X939166D01*
G01X954046Y264511D02*
Y252011D01*
G01X950481Y264511D02*
X957611D01*
G01X969546Y252011D02*
X963346D01*
Y264511D01*
X969546D01*
G01X967066Y258469D02*
X963346D01*
G01X975436Y252011D02*
Y264511D01*
X978536D01*
X979776Y263886D01*
X980706Y263053D01*
X981481Y261803D01*
X982101Y260344D01*
X982256Y258261D01*
X982101Y256178D01*
X981481Y254719D01*
X980706Y253469D01*
X979776Y252636D01*
X978536Y252011D01*
X975436D01*
G01X913746Y364411D02*
Y376911D01*
X917466D01*
X918706Y376286D01*
X919636Y374828D01*
X919946Y373161D01*
X919636Y371494D01*
X918861Y370244D01*
X917466Y369619D01*
X913746D01*
G01X926146Y376911D02*
Y364411D01*
X932346D01*
G01X937771D02*
X941646Y376911D01*
X945521Y364411D01*
G01X944126Y368786D02*
X939166D01*
G01X954046Y376911D02*
Y364411D01*
G01X950481Y376911D02*
X957611D01*
G01X969546Y364411D02*
X963346D01*
Y376911D01*
X969546D01*
G01X967066Y370869D02*
X963346D01*
G01X975436Y364411D02*
Y376911D01*
X978536D01*
X979776Y376286D01*
X980706Y375453D01*
X981481Y374203D01*
X982101Y372744D01*
X982256Y370661D01*
X982101Y368578D01*
X981481Y367119D01*
X980706Y365869D01*
X979776Y365036D01*
X978536Y364411D01*
X975436D01*
G01X913746Y336311D02*
Y348811D01*
X917466D01*
X918706Y348186D01*
X919636Y346728D01*
X919946Y345061D01*
X919636Y343394D01*
X918861Y342144D01*
X917466Y341519D01*
X913746D01*
G01X926146Y348811D02*
Y336311D01*
X932346D01*
G01X937771D02*
X941646Y348811D01*
X945521Y336311D01*
G01X944126Y340686D02*
X939166D01*
G01X954046Y348811D02*
Y336311D01*
G01X950481Y348811D02*
X957611D01*
G01X969546Y336311D02*
X963346D01*
Y348811D01*
X969546D01*
G01X967066Y342769D02*
X963346D01*
G01X975436Y336311D02*
Y348811D01*
X978536D01*
X979776Y348186D01*
X980706Y347353D01*
X981481Y346103D01*
X982101Y344644D01*
X982256Y342561D01*
X982101Y340478D01*
X981481Y339019D01*
X980706Y337769D01*
X979776Y336936D01*
X978536Y336311D01*
X975436D01*
G01X913746Y308211D02*
Y320711D01*
X917466D01*
X918706Y320086D01*
X919636Y318628D01*
X919946Y316961D01*
X919636Y315294D01*
X918861Y314044D01*
X917466Y313419D01*
X913746D01*
G01X926146Y320711D02*
Y308211D01*
X932346D01*
G01X937771D02*
X941646Y320711D01*
X945521Y308211D01*
G01X944126Y312586D02*
X939166D01*
G01X954046Y320711D02*
Y308211D01*
G01X950481Y320711D02*
X957611D01*
G01X969546Y308211D02*
X963346D01*
Y320711D01*
X969546D01*
G01X967066Y314669D02*
X963346D01*
G01X975436Y308211D02*
Y320711D01*
X978536D01*
X979776Y320086D01*
X980706Y319253D01*
X981481Y318003D01*
X982101Y316544D01*
X982256Y314461D01*
X982101Y312378D01*
X981481Y310919D01*
X980706Y309669D01*
X979776Y308836D01*
X978536Y308211D01*
X975436D01*
G01X913746Y422161D02*
Y434661D01*
X917466D01*
X918706Y434036D01*
X919636Y432578D01*
X919946Y430911D01*
X919636Y429244D01*
X918861Y427994D01*
X917466Y427369D01*
X913746D01*
G01X926146Y434661D02*
Y422161D01*
X932346D01*
G01X937771D02*
X941646Y434661D01*
X945521Y422161D01*
G01X944126Y426536D02*
X939166D01*
G01X954046Y434661D02*
Y422161D01*
G01X950481Y434661D02*
X957611D01*
G01X969546Y422161D02*
X963346D01*
Y434661D01*
X969546D01*
G01X967066Y428619D02*
X963346D01*
G01X975436Y422161D02*
Y434661D01*
X978536D01*
X979776Y434036D01*
X980706Y433203D01*
X981481Y431953D01*
X982101Y430494D01*
X982256Y428411D01*
X982101Y426328D01*
X981481Y424869D01*
X980706Y423619D01*
X979776Y422786D01*
X978536Y422161D01*
X975436D01*
G01X913746Y392511D02*
Y405011D01*
X917466D01*
X918706Y404386D01*
X919636Y402928D01*
X919946Y401261D01*
X919636Y399594D01*
X918861Y398344D01*
X917466Y397719D01*
X913746D01*
G01X926146Y405011D02*
Y392511D01*
X932346D01*
G01X937771D02*
X941646Y405011D01*
X945521Y392511D01*
G01X944126Y396886D02*
X939166D01*
G01X954046Y405011D02*
Y392511D01*
G01X950481Y405011D02*
X957611D01*
G01X969546Y392511D02*
X963346D01*
Y405011D01*
X969546D01*
G01X967066Y398969D02*
X963346D01*
G01X975436Y392511D02*
Y405011D01*
X978536D01*
X979776Y404386D01*
X980706Y403553D01*
X981481Y402303D01*
X982101Y400844D01*
X982256Y398761D01*
X982101Y396678D01*
X981481Y395219D01*
X980706Y393969D01*
X979776Y393136D01*
X978536Y392511D01*
X975436D01*
G01X1043946Y139611D02*
Y152111D01*
X1042086Y149611D01*
G01Y139611D02*
X1045806D01*
G01X1052936Y142111D02*
X1053866Y140652D01*
X1055106Y139819D01*
X1056501Y139611D01*
X1057741Y139819D01*
X1058981Y140861D01*
X1059756Y142111D01*
X1059911Y143361D01*
X1059601Y144819D01*
X1058516Y145861D01*
X1057431Y146278D01*
X1056036D01*
G01X1057431D02*
X1058361Y146903D01*
X1059136Y147944D01*
X1059446Y149194D01*
X1059136Y150444D01*
X1058361Y151486D01*
X1056966Y152111D01*
X1055571Y151903D01*
X1054176Y151069D01*
G01X1011396Y440911D02*
Y131811D01*
G01X1050146Y223911D02*
X1051231Y224119D01*
X1052471Y224744D01*
X1053246Y225786D01*
X1053556Y227244D01*
X1053246Y228702D01*
X1052316Y229953D01*
X1050921Y230578D01*
X1049371D01*
X1048441Y230994D01*
X1047666Y232036D01*
X1047356Y233494D01*
X1047821Y234953D01*
X1048906Y235994D01*
X1050146Y236411D01*
X1051386Y235994D01*
X1052471Y234953D01*
X1052936Y233494D01*
X1052626Y232036D01*
X1051851Y230994D01*
X1050921Y230578D01*
X1049371D01*
X1047976Y229953D01*
X1047046Y228702D01*
X1046736Y227244D01*
X1047046Y225786D01*
X1047821Y224744D01*
X1049061Y224119D01*
X1050146Y223911D01*
G01Y195811D02*
Y208311D01*
X1048286Y205811D01*
G01Y195811D02*
X1052006D01*
G01X1047201Y178128D02*
X1048131Y179377D01*
X1049216Y180003D01*
X1050456Y180211D01*
X1052006Y179794D01*
X1053091Y178753D01*
X1053401Y177503D01*
X1053246Y176252D01*
X1052626Y175211D01*
X1049526Y173128D01*
X1048131Y171669D01*
X1047201Y169586D01*
X1046891Y167711D01*
X1053401D01*
G01X1052006Y280111D02*
Y292611D01*
X1046271Y283653D01*
X1054021D01*
G01X1043946Y252011D02*
Y264511D01*
X1042086Y262011D01*
G01Y252011D02*
X1045806D01*
G01X1053401Y262428D02*
X1054331Y263677D01*
X1055416Y264303D01*
X1056656Y264511D01*
X1058206Y264094D01*
X1059291Y263053D01*
X1059601Y261803D01*
X1059446Y260552D01*
X1058826Y259511D01*
X1055726Y257428D01*
X1054331Y255969D01*
X1053401Y253886D01*
X1053091Y252011D01*
X1059601D01*
G01X1041001Y369619D02*
X1042086Y371078D01*
X1043016Y371911D01*
X1044256Y372328D01*
X1045341Y371911D01*
X1046116Y371078D01*
X1046736Y369828D01*
X1046891Y368369D01*
X1046736Y367119D01*
X1046116Y365869D01*
X1045186Y364828D01*
X1044101Y364411D01*
X1042861Y364828D01*
X1041776Y366077D01*
X1041156Y367953D01*
X1041001Y370036D01*
X1041311Y372744D01*
X1041776Y374203D01*
X1042551Y375661D01*
X1043636Y376703D01*
X1044721Y376911D01*
X1045806Y376494D01*
X1046581Y375453D01*
G01X1053401Y369619D02*
X1054486Y371078D01*
X1055416Y371911D01*
X1056656Y372328D01*
X1057741Y371911D01*
X1058516Y371078D01*
X1059136Y369828D01*
X1059291Y368369D01*
X1059136Y367119D01*
X1058516Y365869D01*
X1057586Y364828D01*
X1056501Y364411D01*
X1055261Y364828D01*
X1054176Y366077D01*
X1053556Y367953D01*
X1053401Y370036D01*
X1053711Y372744D01*
X1054176Y374203D01*
X1054951Y375661D01*
X1056036Y376703D01*
X1057121Y376911D01*
X1058206Y376494D01*
X1058981Y375453D01*
G01X1050146Y336311D02*
X1051231Y336519D01*
X1052471Y337144D01*
X1053246Y338186D01*
X1053556Y339644D01*
X1053246Y341102D01*
X1052316Y342353D01*
X1050921Y342978D01*
X1049371D01*
X1048441Y343394D01*
X1047666Y344436D01*
X1047356Y345894D01*
X1047821Y347353D01*
X1048906Y348394D01*
X1050146Y348811D01*
X1051386Y348394D01*
X1052471Y347353D01*
X1052936Y345894D01*
X1052626Y344436D01*
X1051851Y343394D01*
X1050921Y342978D01*
X1049371D01*
X1047976Y342353D01*
X1047046Y341102D01*
X1046736Y339644D01*
X1047046Y338186D01*
X1047821Y337144D01*
X1049061Y336519D01*
X1050146Y336311D01*
G01X1041001Y318628D02*
X1041931Y319877D01*
X1043016Y320503D01*
X1044256Y320711D01*
X1045806Y320294D01*
X1046891Y319253D01*
X1047201Y318003D01*
X1047046Y316752D01*
X1046426Y315711D01*
X1043326Y313628D01*
X1041931Y312169D01*
X1041001Y310086D01*
X1040691Y308211D01*
X1047201D01*
G01X1053401Y318628D02*
X1054331Y319877D01*
X1055416Y320503D01*
X1056656Y320711D01*
X1058206Y320294D01*
X1059291Y319253D01*
X1059601Y318003D01*
X1059446Y316752D01*
X1058826Y315711D01*
X1055726Y313628D01*
X1054331Y312169D01*
X1053401Y310086D01*
X1053091Y308211D01*
X1059601D01*
G01X1037746Y422161D02*
X1036506Y422369D01*
X1035421Y423202D01*
X1034491Y424453D01*
X1033871Y425911D01*
X1033561Y427578D01*
Y429244D01*
X1033871Y430911D01*
X1034491Y432369D01*
X1035421Y433619D01*
X1036506Y434453D01*
X1037746Y434661D01*
X1038986Y434453D01*
X1040071Y433619D01*
X1041001Y432369D01*
X1041621Y430911D01*
X1041931Y429244D01*
Y427578D01*
X1041621Y425911D01*
X1041001Y424453D01*
X1040071Y423202D01*
X1038986Y422369D01*
X1037746Y422161D01*
G01X1038986Y425494D02*
X1040846Y422161D01*
G01X1050146Y434661D02*
Y422161D01*
G01X1046581Y434661D02*
X1053711D01*
G01X1062546Y422161D02*
Y427786D01*
X1059446Y434661D01*
G01X1065646D02*
X1062546Y427786D01*
G01X1037746Y392511D02*
Y405011D01*
X1035886Y402511D01*
G01Y392511D02*
X1039606D01*
G01X1049836D02*
X1050146Y395219D01*
X1050611Y397511D01*
X1051231Y399594D01*
X1052006Y401886D01*
X1053246Y405011D01*
X1047046D01*
G01X1064406Y392511D02*
Y405011D01*
X1058671Y396053D01*
X1066421D01*
G01X-11811Y-26378D02*
G03X-7874Y-22441I0J3937D01*
G01X-31496Y-11378D02*
G03X-16496Y-26378I15000J0D01*
G01X0Y-18504D02*
G03X-7874I-3937J0D01*
G01X-11811Y-26378D02*
X-16496D01*
G01X-31496Y727913D02*
Y-11378D01*
G01X-7874Y-18504D02*
Y-22441D01*
G01Y20866D02*
G03X0I3937J0D01*
G01X-14607Y16741D02*
G03I-4291J0D01*
G01X-7874Y175427D02*
Y20866D01*
G01X-11608Y217029D02*
G03X-19685Y205824I3734J-11205D01*
G01X-9118Y209559D02*
G03X-11811Y205824I1244J-3735D01*
G01X-19685Y187877D02*
G03X-11608Y176672I11811J0D01*
G01X-11811Y187877D02*
G03X-9118Y184142I3937J0D01*
G01X-7874Y175427D02*
X-11609Y176672D01*
G01X-2692Y182000D02*
X-9119Y184142D01*
G01X-7874Y218273D02*
X-11609Y217029D01*
G01X-2692Y211701D02*
X-9119Y209559D01*
G01X-7874Y307086D02*
Y218273D01*
G01X-19685Y205824D02*
Y187877D01*
G01X-11811Y205824D02*
Y187877D01*
G01X0Y370079D02*
G03X-7874I-3937J0D01*
G01Y346456D02*
G03X0I3937J0D01*
G01Y307086D02*
G03X-7874I-3937J0D01*
G01Y370079D02*
Y346456D01*
G01Y409449D02*
G03X0I3937J0D01*
G01X-7874Y564010D02*
Y409449D01*
G01X-11608Y605612D02*
G03X-19685Y594406I3735J-11206D01*
G01X-9118Y598141D02*
G03X-11811Y594406I1244J-3735D01*
G01X-19685Y576459D02*
G03X-11608Y565254I11811J0D01*
G01X-11811Y576459D02*
G03X-9118Y572724I3937J0D01*
G01X-7874Y564010D02*
X-11609Y565255D01*
G01X-2692Y570582D02*
X-9119Y572725D01*
G01X-2692Y600284D02*
X-9119Y598141D01*
G01X-19685Y594406D02*
Y576459D01*
G01X-11811Y594406D02*
Y576459D01*
G01X-7874Y606856D02*
X-11609Y605611D01*
G01X-7874Y695669D02*
Y606856D01*
G01X-13215Y723144D02*
G03I-4291J0D01*
G01X-7874Y738976D02*
G03X-11811Y742913I-3937J0D01*
G01X-16496D02*
G03X-31496Y727913I0J-15000D01*
G01X-7874Y735039D02*
G03X0I3937J0D01*
G01Y695669D02*
G03X-7874I-3937J0D01*
G01X-11811Y742913D02*
X-16496D01*
G01X-7874Y738976D02*
Y735039D01*
G01X218339Y-26378D02*
X203603D01*
G02X201634Y-24410I0J1969D01*
G01Y-788D01*
G03X199666Y1181I-1968J1D01*
G01X33012D01*
G03X31044Y-788I0J-1968D01*
G01Y-24410D01*
G02X29075Y-26378I-1969J1D01*
G01X14339D01*
G01X29075D02*
G03X31044Y-24410I0J1969D01*
G01D02*
Y-788D01*
G01X0Y-22441D02*
G03X3937Y-26378I3937J0D01*
G01X0Y178265D02*
Y-22441D01*
G01X3937Y-26378D02*
X29075D01*
G01X44390Y5118D02*
G03I-2658J0D01*
G01X33012Y1181D02*
G03X31044Y-788I0J-1968D01*
G01X33012Y1181D02*
X199666D01*
G01X71407Y128987D02*
G03X76975Y134555I2784J2784D01*
G01X64567Y137457D02*
G03X65720Y134673I3938J0D01*
G01D02*
X94910Y105484D01*
G01X64567Y137457D02*
Y249131D01*
G01X-2692Y211701D02*
G03X0Y215436I-1245J3735D01*
G01Y178265D02*
G03X-2692Y182000I-3937J0D01*
G01X0Y350394D02*
Y215436D01*
G01X64567Y286302D02*
G03X67259Y282567I3937J0D01*
G01Y252866D02*
G03X64567Y249131I1245J-3735D01*
G01X73686Y280425D02*
X67259Y282567D01*
G01X64567Y286302D02*
Y350394D01*
G01X73686Y255008D02*
X67259Y252866D01*
G01X64567Y346456D02*
G03X72441I3937J0D01*
G01Y321260D02*
G03X64567I-3937J0D01*
G01X29075Y362205D02*
G03X31044Y364173I0J1969D01*
G01X0Y366142D02*
G03X3937Y362205I3937J0D01*
G01X31044Y364173D02*
Y387795D01*
G01X0Y566847D02*
Y366142D01*
G01X3937Y362205D02*
X29075D01*
G01X64567Y350394D02*
G03X60630Y354331I-3937J0D01*
G01X3937D02*
G03X0Y350394I0J-3937D01*
G01X60630Y354331D02*
X3937D01*
G01X44390Y393701D02*
G03I-2658J0D01*
G01X33012Y389764D02*
G03X31044Y387795I0J-1968D01*
G01X33012Y389764D02*
X199666D01*
G01X71407Y517570D02*
G03X76975Y523137I2784J2784D01*
G01X64567Y526040D02*
G03X65720Y523256I3938J0D01*
G01D02*
X94910Y494066D01*
G01X64567Y526040D02*
Y637713D01*
G01X-2692Y600283D02*
G03X0Y604019I-1245J3735D01*
G01Y566847D02*
G03X-2692Y570582I-3937J0D01*
G01X64567Y674885D02*
G03X67259Y671150I3937J0D01*
G01Y641448D02*
G03X64567Y637713I1245J-3735D01*
G01X73686Y669007D02*
X67259Y671150D01*
G01X64567Y674885D02*
Y738976D01*
G01X73686Y643591D02*
X67259Y641448D01*
G01X0Y738976D02*
Y604019D01*
G01X64567Y735039D02*
G03X72441I3937J0D01*
G01Y709842D02*
G03X64567I-3937J0D01*
G01Y738976D02*
G03X60630Y742913I-3937J0D01*
G01X3937D02*
G03X0Y738976I0J-3937D01*
G01X60630Y742913D02*
X3937D01*
G01X102882Y-6532D02*
X102349Y-6199D01*
X101749Y-5999D01*
X101215D01*
X100682Y-6199D01*
X100282Y-6532D01*
X100082Y-6999D01*
X100215Y-7466D01*
X100549Y-7866D01*
X101149Y-8132D01*
X101949Y-8266D01*
X102415Y-8532D01*
X102615Y-8999D01*
X102482Y-9466D01*
X102149Y-9799D01*
X101682Y-9999D01*
X101215D01*
X100749Y-9866D01*
X100349Y-9532D01*
G01X96882Y-5999D02*
Y-9999D01*
G01X92282Y-8666D02*
Y-5999D01*
G01Y-9732D02*
X92415Y-9799D01*
Y-9932D01*
X92282Y-9999D01*
X92149Y-9932D01*
Y-9799D01*
X92282Y-9732D01*
G01X87682Y-9999D02*
Y-5999D01*
G01X88615Y-8666D02*
X86749D01*
G01X94518Y597D02*
X92518Y-1403D01*
X96518D01*
X94518Y597D01*
Y-5403D01*
G01X127362Y78740D02*
G03I-11023J0D01*
G01X118788Y137176D02*
G03I-4291J0D01*
G01X94791Y116738D02*
G03X89224Y111170I-2784J-2784D01*
G01X143454D02*
G03X137886Y116738I-2784J2784D01*
G01X134984Y104331D02*
G03X137768Y105484I0J3938D01*
G01X94910D02*
G03X97694Y104331I2784J2785D01*
G01X137886Y116738D02*
X133353Y112205D01*
G01X166957Y134673D02*
X137768Y105484D01*
G01X94791Y116738D02*
X99325Y112205D01*
G01X72441Y139088D02*
X76975Y134555D01*
G01X72441Y139088D02*
Y246293D01*
G01X133353Y112205D02*
X99325D01*
G01X134984Y104331D02*
X97694D01*
G01X84252Y276690D02*
G03X76175Y287895I-11811J0D01*
G01X76378Y276690D02*
G03X73686Y280425I-3937J0D01*
G01X76175Y247538D02*
G03X84252Y258743I-3734J11205D01*
G01X73686Y255008D02*
G03X76378Y258743I-1245J3735D01*
G01X76176Y287895D02*
X72441Y289140D01*
G01X84252Y258743D02*
Y276690D01*
G01X76378Y258743D02*
Y276690D01*
G01X72441Y289140D02*
Y321260D01*
G01X76176Y247538D02*
X72441Y246293D01*
G01X119874Y329366D02*
G03I-4291J0D01*
G01X76378Y354331D02*
G03X72441Y350394I0J-3937D01*
G01X76378Y354331D02*
X156299D01*
G01X72441Y346456D02*
Y350394D01*
G01X118788Y525759D02*
G03I-4291J0D01*
G01X94791Y505321D02*
G03X89224Y499753I-2784J-2784D01*
G01X143454D02*
G03X137886Y505321I-2784J2784D01*
G01D02*
X133353Y500787D01*
G01X94791Y505321D02*
X99325Y500787D01*
G01X72441Y527671D02*
X76975Y523137D01*
G01X133353Y500787D02*
X99325D01*
G01X134984Y492913D02*
G03X137768Y494066I0J3938D01*
G01X127362Y467323D02*
G03I-11023J0D01*
G01X94910Y494066D02*
G03X97694Y492913I2784J2785D01*
G01X166957Y523256D02*
X137768Y494066D01*
G01X134984Y492913D02*
X97694D01*
G01X72441Y527671D02*
Y634876D01*
G01X84252Y665272D02*
G03X76175Y676478I-11812J0D01*
G01Y636120D02*
G03X84252Y647326I-3735J11206D01*
G01X76176Y676477D02*
X72441Y677722D01*
G01X84252Y647326D02*
Y665272D01*
G01X72441Y677722D02*
Y709842D01*
G01X76176Y636121D02*
X72441Y634876D01*
G01X76378Y665272D02*
G03X73686Y669007I-3937J0D01*
G01Y643591D02*
G03X76378Y647326I-1245J3735D01*
G01D02*
Y665272D01*
G01X119874Y717948D02*
G03I-4291J0D01*
G01X76378Y742913D02*
G03X72441Y738976I0J-3937D01*
G01X76378Y742913D02*
X156299D01*
G01X72441Y735039D02*
Y738976D01*
G01X201634Y-24410D02*
G03X203603Y-26378I1968J0D01*
G01X201634Y-788D02*
Y-24410D01*
G01X203603Y-26378D02*
X228740D01*
G01X193603Y5118D02*
G03I-2658J0D01*
G01X201634Y-788D02*
G03X199666Y1181I-1969J0D01*
G01X155703Y134555D02*
G03X161271Y128987I2784J-2784D01*
G01X166957Y134673D02*
G03X168110Y137457I-2785J2784D01*
G01X160236Y139088D02*
X155703Y134555D01*
G01X160236Y246293D02*
Y139088D01*
G01X168110Y249131D02*
Y137457D01*
G01X165418Y282567D02*
G03X168110Y286302I-1245J3735D01*
G01X156502Y287895D02*
G03X148425Y276690I3734J-11205D01*
G01X158992Y280425D02*
G03X156299Y276690I1244J-3735D01*
G01X168110Y249131D02*
G03X165418Y252866I-3937J0D01*
G01X148425Y258743D02*
G03X156502Y247538I11811J0D01*
G01X156299Y258743D02*
G03X158992Y255008I3937J0D01*
G01X160236Y246293D02*
X156501Y247538D01*
G01X165418Y252866D02*
X158991Y255008D01*
G01X160236Y321260D02*
Y289140D01*
G01X168110Y350394D02*
Y286302D01*
G01X148425Y276690D02*
Y258743D01*
G01X156299Y276690D02*
Y258743D01*
G01X160236Y289140D02*
X156501Y287895D01*
G01X165418Y282567D02*
X158991Y280425D01*
G01X225227Y362205D02*
G03Y354331I0J-3937D01*
G01X207116D02*
G03Y362205I0J3937D01*
G01X160236Y346456D02*
G03X168110I3937J0D01*
G01Y321260D02*
G03X160236I-3937J0D01*
G01Y350394D02*
G03X156299Y354331I-3937J0D01*
G01X201634Y364173D02*
G03X203603Y362205I1968J0D01*
G01X201634Y387795D02*
Y364173D01*
G01X203603Y362205D02*
X228740D01*
G01X172047Y354331D02*
G03X168110Y350394I0J-3937D01*
G01X228740Y354331D02*
X172047D01*
G01X160236Y350394D02*
Y346456D01*
G01X193603Y393701D02*
G03I-2658J0D01*
G01X201634Y387795D02*
G03X199666Y389764I-1969J0D01*
G01X155703Y523137D02*
G03X161271Y517570I2784J-2783D01*
G01X160236Y527671D02*
X155703Y523137D01*
G01X166957Y523256D02*
G03X168110Y526040I-2785J2784D01*
G01Y637713D02*
Y526040D01*
G01X160236Y634876D02*
Y527671D01*
G01X156502Y676478D02*
G03X148425Y665272I3735J-11206D01*
G01Y647326D02*
G03X156502Y636120I11812J0D01*
G01X160236Y634876D02*
X156501Y636121D01*
G01X160236Y709842D02*
Y677722D01*
G01X148425Y665272D02*
Y647326D01*
G01X160236Y677722D02*
X156501Y676477D01*
G01X165418Y671150D02*
G03X168110Y674885I-1245J3735D01*
G01X158992Y669007D02*
G03X156299Y665272I1244J-3735D01*
G01X168110Y637713D02*
G03X165418Y641448I-3937J0D01*
G01X156299Y647326D02*
G03X158992Y643591I3937J0D01*
G01X165418Y641448D02*
X158991Y643591D01*
G01X168110Y738976D02*
Y674885D01*
G01X156299Y665272D02*
Y647326D01*
G01X165418Y671150D02*
X158991Y669007D01*
G01X160236Y735039D02*
G03X168110I3937J0D01*
G01Y709842D02*
G03X160236I-3937J0D01*
G01Y738976D02*
G03X156299Y742913I-3937J0D01*
G01X160236Y738976D02*
Y735039D01*
G01X172047Y742913D02*
G03X168110Y738976I0J-3937D01*
G01X228740Y742913D02*
X172047D01*
G01X236614Y-14567D02*
X244488D01*
G01X236614D02*
G03X232677Y-18504I0J-3937D01*
G01X248425D02*
G03X244488Y-14567I-3937J0D01*
G01X248425Y-22441D02*
G03X252362Y-26378I3937J0D01*
G01D02*
X309055D01*
G01X248425Y112921D02*
Y-22441D01*
G01X228740Y-26378D02*
G03X232677Y-22441I0J3937D01*
G01D02*
Y178669D01*
G01X236614Y16929D02*
X244488D01*
G01X232677Y20866D02*
G03X236614Y16929I3937J0D01*
G01X244488D02*
G03X248425Y20866I0J3937D01*
G01X246249Y145762D02*
G03X248425Y149283I-1761J3521D01*
G01Y112921D02*
G03X246249Y116442I-3937J0D01*
G01X242727Y144001D02*
G03X240551Y140480I1761J-3521D01*
G01Y121724D02*
G03X242727Y118203I3937J0D01*
G01X240551Y140480D02*
Y121724D01*
G01X242728Y118203D02*
X246249Y116442D01*
G01X242728Y144001D02*
X246249Y145762D01*
G01X248425Y350394D02*
Y149283D01*
G01X234853Y182190D02*
G03X232677Y178669I1761J-3521D01*
G01Y215031D02*
G03X234853Y211510I3937J0D01*
G01X238375Y183951D02*
G03X240551Y187472I-1761J3521D01*
G01Y206228D02*
G03X238375Y209749I-3937J0D01*
G01X240551Y187472D02*
Y206228D01*
G01X232677Y215031D02*
Y350394D01*
G01X238375Y209749D02*
X234854Y211510D01*
G01X238375Y183951D02*
X234854Y182190D01*
G01X273986Y362205D02*
G03Y354331I0J-3937D01*
G01X255876D02*
G03Y362205I0J3937D01*
G01X236614Y374016D02*
X244488D01*
G01X236614D02*
G03X232677Y370079I0J-3937D01*
G01X248425D02*
G03X244488Y374016I-3937J0D01*
G01X236614Y342519D02*
X244488D01*
G01X236614Y311023D02*
X244488D01*
G01X236614D02*
G03X232677Y307086I0J-3937D01*
G01Y346456D02*
G03X236614Y342519I3937J0D01*
G01X244488D02*
G03X248425Y346456I0J3937D01*
G01Y307086D02*
G03X244488Y311023I-3937J0D01*
G01X248425Y366142D02*
G03X252362Y362205I3937J0D01*
G01D02*
X309055D01*
G01X248425Y501504D02*
Y366142D01*
G01X228740Y362205D02*
G03X232677Y366142I0J3937D01*
G01D02*
Y567252D01*
G01X279469Y352362D02*
G03X277500Y354331I-1969J0D01*
G01X252362D02*
G03X248425Y350394I0J-3937D01*
G01X292815Y322834D02*
G03I-2657J0D01*
G01X279469Y328740D02*
G03X281437Y326771I1969J0D01*
G01X279469Y328740D02*
Y352362D01*
G01X448091Y326771D02*
X281437D01*
G01X277500Y354331D02*
X252362D01*
G01X232677Y350394D02*
G03X228740Y354331I-3937J0D01*
G01X236614Y405512D02*
X244488D01*
G01X232677Y409449D02*
G03X236614Y405512I3937J0D01*
G01X244488D02*
G03X248425Y409449I0J3937D01*
G01Y501504D02*
G03X246249Y505025I-3937J0D01*
G01X240551Y510307D02*
G03X242727Y506786I3937J0D01*
G01X240551Y529063D02*
Y510307D01*
G01X242728Y506786D02*
X246249Y505025D01*
G01Y534345D02*
G03X248425Y537866I-1761J3521D01*
G01X242727Y532584D02*
G03X240551Y529063I1761J-3521D01*
G01X248425Y738976D02*
Y537866D01*
G01X242728Y532584D02*
X246249Y534345D01*
G01X234853Y570773D02*
G03X232677Y567252I1761J-3521D01*
G01Y603614D02*
G03X234853Y600093I3937J0D01*
G01X238375Y572534D02*
G03X240551Y576055I-1761J3521D01*
G01Y594811D02*
G03X238375Y598332I-3937J0D01*
G01X240551Y576055D02*
Y594811D01*
G01X238375Y598332D02*
X234854Y600093D01*
G01X238375Y572534D02*
X234854Y570773D01*
G01X232677Y603614D02*
Y738976D01*
G01X236614Y731102D02*
X244488D01*
G01X236614Y699606D02*
X244488D01*
G01X236614D02*
G03X232677Y695669I0J-3937D01*
G01Y735039D02*
G03X236614Y731102I3937J0D01*
G01X244488D02*
G03X248425Y735039I0J3937D01*
G01Y695669D02*
G03X244488Y699606I-3937J0D01*
G01X279469Y740945D02*
G03X277500Y742913I-1968J0D01*
G01X252362D02*
G03X248425Y738976I0J-3937D01*
G01X292815Y711417D02*
G03I-2657J0D01*
G01X279469Y717323D02*
G03X281437Y715354I1969J0D01*
G01X279469Y717323D02*
Y740945D01*
G01X448091Y715354D02*
X281437D01*
G01X277500Y742913D02*
X252362D01*
G01X232677Y738976D02*
G03X228740Y742913I-3937J0D01*
G01X369811Y-1413D02*
G03I-4291J0D01*
G01X320866Y-18504D02*
G03X312992I-3937J0D01*
G01X320866Y-22441D02*
G03X324803Y-26378I3937J0D01*
G01X404725D02*
X324803D01*
G01X320866Y-22441D02*
Y-18504D01*
G01X309055Y-26378D02*
G03X312992Y-22441I0J3937D01*
G01D02*
Y41650D01*
G01Y6693D02*
G03X320866I3937J0D01*
G01X324600Y40057D02*
G03X332677Y51263I-3735J11206D01*
G01Y69209D02*
G03X324600Y80415I-11812J0D01*
G01X320866Y6693D02*
Y38813D01*
G01X332677Y51263D02*
Y69209D01*
G01X320866Y38813D02*
X324601Y40058D01*
G01X315685Y45385D02*
G03X312992Y41650I1244J-3735D01*
G01X322111Y47528D02*
G03X324803Y51263I-1245J3735D01*
G01Y69209D02*
G03X322111Y72944I-3937J0D01*
G01X324803Y51263D02*
Y69209D01*
G01X315684Y45385D02*
X322111Y47528D01*
G01X320866Y81659D02*
X324601Y80414D01*
G01X320866Y81659D02*
Y188864D01*
G01X312992Y78822D02*
G03X315685Y75087I3937J0D01*
G01X315684D02*
X322111Y72944D01*
G01X312992Y78822D02*
Y190495D01*
G01X370897Y190776D02*
G03I-4291J0D01*
G01X337649Y216782D02*
G03X343217Y211214I2784J-2784D01*
G01X325400Y193398D02*
G03X319832Y198965I-2784J2784D01*
G01X343217Y211214D02*
X347750Y215748D01*
G01X320866Y188864D02*
X325400Y193398D01*
G01X347750Y215748D02*
X381778D01*
G01X314145Y193279D02*
G03X312992Y190495I2785J-2784D01*
G01X346119Y223622D02*
G03X343335Y222469I0J-3938D01*
G01X314145Y193279D02*
X343335Y222469D01*
G01X375788Y249212D02*
G03I-11024J0D01*
G01X346119Y223622D02*
X383409D01*
G01X320866Y370079D02*
G03X312992I-3937J0D01*
G01X320866Y366142D02*
G03X324803Y362205I3937J0D01*
G01X404725D02*
X324803D01*
G01X320866Y366142D02*
Y370079D01*
G01X309055Y362205D02*
G03X312992Y366142I0J3937D01*
G01D02*
Y430233D01*
G01X369811Y387169D02*
G03I-4291J0D01*
G01X312992Y395275D02*
G03X320866I3937J0D01*
G01X324600Y428640D02*
G03X332677Y439845I-3734J11205D01*
G01X320866Y395275D02*
Y427395D01*
G01X332677Y439845D02*
Y457792D01*
G01X320866Y427395D02*
X324601Y428640D01*
G01X315685Y433968D02*
G03X312992Y430233I1244J-3735D01*
G01X322111Y436110D02*
G03X324803Y439845I-1245J3735D01*
G01D02*
Y457792D01*
G01X315684Y433968D02*
X322111Y436110D01*
G01X332677Y457792D02*
G03X324600Y468997I-11811J0D01*
G01X320866Y470242D02*
X324601Y468997D01*
G01X320866Y470242D02*
Y577447D01*
G01X312992Y467404D02*
G03X315685Y463669I3937J0D01*
G01X324803Y457792D02*
G03X322111Y461527I-3937J0D01*
G01X315684Y463669D02*
X322111Y461527D01*
G01X312992Y467404D02*
Y579078D01*
G01X370897Y579359D02*
G03I-4291J0D01*
G01X337649Y605365D02*
G03X343217Y599797I2784J-2784D01*
G01X325400Y581980D02*
G03X319832Y587548I-2784J2784D01*
G01X343217Y599797D02*
X347750Y604331D01*
G01X320866Y577447D02*
X325400Y581980D01*
G01X314145Y581862D02*
G03X312992Y579078I2785J-2784D01*
G01X314145Y581862D02*
X343335Y611051D01*
G01X347750Y604331D02*
X381778D01*
G01X346119Y612205D02*
G03X343335Y611051I1J-3937D01*
G01X375788Y637795D02*
G03I-11024J0D01*
G01X346119Y612205D02*
X383409D01*
G01X416536Y-18504D02*
G03X408662I-3937J0D01*
G01X404725Y-26378D02*
G03X408662Y-22441I0J3937D01*
G01Y-18504D02*
Y-22441D01*
G01X416536D02*
G03X420473Y-26378I3937J0D01*
G01D02*
X477166D01*
G01X416536Y41650D02*
Y-22441D01*
G01X408662Y6693D02*
G03X416536I3937J0D01*
G01X396851Y51263D02*
G03X404928Y40057I11812J0D01*
G01Y80415D02*
G03X396851Y69209I3735J-11206D01*
G01X404927Y40058D02*
X408662Y38813D01*
G01X396851Y69209D02*
Y51263D01*
G01X408662Y38813D02*
Y6693D01*
G01X416536Y41650D02*
G03X413843Y45385I-3937J0D01*
G01X404725Y51263D02*
G03X407417Y47528I3937J0D01*
G01Y72944D02*
G03X404725Y69209I1245J-3735D01*
G01X407417Y47528D02*
X413844Y45385D01*
G01X404725Y69209D02*
Y51263D01*
G01X408662Y188864D02*
Y81659D01*
G01X404927Y80414D02*
X408662Y81659D01*
G01X413843Y75087D02*
G03X416536Y78822I-1244J3735D01*
G01Y190495D02*
Y78822D01*
G01X407417Y72944D02*
X413844Y75087D01*
G01X409696Y198965D02*
G03X404128Y193398I-2784J-2783D01*
G01X386311Y211214D02*
G03X391879Y216782I2784J2784D01*
G01X386311Y211214D02*
X381778Y215748D01*
G01X408662Y188864D02*
X404128Y193398D01*
G01X386193Y222469D02*
G03X383409Y223622I-2784J-2785D01*
G01X416536Y190495D02*
G03X415383Y193279I-3938J0D01*
G01D02*
X386193Y222469D01*
G01X416536Y370079D02*
G03X408662I-3937J0D01*
G01X404725Y362205D02*
G03X408662Y366142I0J3937D01*
G01Y370079D02*
Y366142D01*
G01X416536D02*
G03X420473Y362205I3937J0D01*
G01D02*
X477166D01*
G01X416536Y430233D02*
Y366142D01*
G01X442028Y322834D02*
G03I-2658J0D01*
G01X448091Y326771D02*
G03X450059Y328740I0J1968D01*
G01X452028Y354331D02*
G03X450059Y352362I0J-1969D01*
G01D02*
Y328740D01*
G01X408662Y395275D02*
G03X416536I3937J0D01*
G01X396851Y439845D02*
G03X404928Y428640I11811J0D01*
G01X404927D02*
X408662Y427395D01*
G01X396851Y457792D02*
Y439845D01*
G01X408662Y427395D02*
Y395275D01*
G01X416536Y430233D02*
G03X413843Y433968I-3937J0D01*
G01X404725Y439845D02*
G03X407417Y436110I3937J0D01*
G01D02*
X413844Y433968D01*
G01X404725Y457792D02*
Y439845D01*
G01X404928Y468997D02*
G03X396851Y457792I3734J-11205D01*
G01X408662Y577447D02*
Y470242D01*
G01X404927Y468997D02*
X408662Y470242D01*
G01X413843Y463669D02*
G03X416536Y467404I-1244J3735D01*
G01X407417Y461527D02*
G03X404725Y457792I1245J-3735D01*
G01X416536Y579078D02*
Y467404D01*
G01X407417Y461527D02*
X413844Y463669D01*
G01X409696Y587548D02*
G03X404128Y581980I-2784J-2784D01*
G01X386311Y599797D02*
G03X391879Y605365I2784J2784D01*
G01X386311Y599797D02*
X381778Y604331D01*
G01X408662Y577447D02*
X404128Y581980D01*
G01X416536Y579078D02*
G03X415383Y581862I-3938J0D01*
G01D02*
X386193Y611051D01*
G01D02*
G03X383409Y612205I-2785J-2783D01*
G01X442028Y711417D02*
G03I-2658J0D01*
G01X448091Y715354D02*
G03X450059Y717323I0J1968D01*
G01X452028Y742913D02*
G03X450059Y740945I0J-1969D01*
G01D02*
Y717323D01*
G01X488977Y-22441D02*
G03X492914Y-26378I3937J0D01*
G01X497599D02*
G03X512599Y-11378I0J15000D01*
G01X488977Y-18504D02*
G03X481103I-3937J0D01*
G01X492914Y-26378D02*
X497599D01*
G01X512599Y-11378D02*
Y455139D01*
G01X488977Y-22441D02*
Y-18504D01*
G01X477166Y-26378D02*
G03X481103Y-22441I0J3937D01*
G01D02*
Y112517D01*
G01Y20866D02*
G03X488977I3937J0D01*
G01D02*
Y109679D01*
G01X492711Y110924D02*
G03X500788Y122129I-3734J11205D01*
G01Y140076D02*
G03X492711Y151281I-11811J0D01*
G01X488977Y109679D02*
X492712Y110924D01*
G01X500788Y122129D02*
Y140076D01*
G01X483795Y116252D02*
G03X481103Y112517I1245J-3735D01*
G01Y149688D02*
G03X483795Y145953I3937J0D01*
G01X490221Y118394D02*
G03X492914Y122129I-1244J3735D01*
G01Y140076D02*
G03X490221Y143811I-3937J0D01*
G01X483795Y145953D02*
X490222Y143811D01*
G01X483795Y116251D02*
X490222Y118394D01*
G01X492914Y122129D02*
Y140076D01*
G01X488977Y152525D02*
X492712Y151280D01*
G01X488977Y152525D02*
Y307086D01*
G01X481103Y149688D02*
Y350394D01*
G01X488977Y307086D02*
G03X481103I-3937J0D01*
G01Y346456D02*
G03X488977I3937J0D01*
G01Y370079D02*
G03X481103I-3937J0D01*
G01X488977Y346456D02*
Y370079D01*
G01X477166Y362205D02*
G03X481103Y366142I0J3937D01*
G01D02*
Y501099D01*
G01Y350394D02*
G03X477166Y354331I-3937J0D01*
G01D02*
X452028D01*
G01X481103Y409449D02*
G03X488977I3937J0D01*
G01D02*
Y498262D01*
G01X512599Y463013D02*
G03Y455139I0J-3937D01*
G01Y463013D02*
Y727913D01*
G01X492711Y499506D02*
G03X500788Y510711I-3734J11205D01*
G01X488977Y498262D02*
X492712Y499507D01*
G01X500788Y510711D02*
Y528658D01*
G01X483795Y504834D02*
G03X481103Y501099I1245J-3735D01*
G01X490221Y506976D02*
G03X492914Y510711I-1244J3735D01*
G01X483795Y504834D02*
X490222Y506976D01*
G01X492914Y510711D02*
Y528658D01*
G01X500788D02*
G03X492711Y539863I-11811J0D01*
G01X488977Y541108D02*
X492712Y539863D01*
G01X488977Y541108D02*
Y695669D01*
G01X481103Y538271D02*
G03X483795Y534535I3937J-1D01*
G01X492914Y528658D02*
G03X490221Y532393I-3937J0D01*
G01X483795Y534536D02*
X490222Y532393D01*
G01X481103Y538271D02*
Y738976D01*
G01X499107Y713716D02*
G03I-4291J0D01*
G01X492914Y742913D02*
G03X488977Y738976I0J-3937D01*
G01X512599Y727913D02*
G03X497599Y742913I-15000J0D01*
G01X488977Y695669D02*
G03X481103I-3937J0D01*
G01Y735039D02*
G03X488977I3937J0D01*
G01X492914Y742913D02*
X497599D01*
G01X488977Y735039D02*
Y738976D01*
G01X481103D02*
G03X477166Y742913I-3937J0D01*
G01D02*
X452028D01*
G54D12*
X41752Y5118D03*
X190926D03*
X650246Y173961D03*
G54D13*
X48000Y38000D03*
X58700Y55600D03*
X33200Y59100D03*
X35744Y51944D03*
X41000Y36900D03*
X50100Y20700D03*
X57450Y35400D03*
X55500Y42000D03*
X69446Y48262D03*
X70360Y25750D03*
X73000Y57200D03*
X57400Y26400D03*
X63300Y37300D03*
X43900Y59600D03*
X42300Y51900D03*
X50100Y34500D03*
X68838Y12300D03*
X39400Y41000D03*
X36900Y17600D03*
X26000Y51600D03*
X19763Y92200D03*
X55700Y121400D03*
X22800Y112600D03*
X32100Y114900D03*
X42500Y115000D03*
X47300Y107940D03*
X34900Y106742D03*
X37100Y73960D03*
X37500Y87300D03*
X17700Y89400D03*
X50400Y118300D03*
X24000Y120900D03*
X41492Y106258D03*
X27200Y104100D03*
X33100Y73900D03*
X32200Y91400D03*
X40000Y77100D03*
X23093Y99967D03*
X9000Y81250D03*
Y77250D03*
X40900Y88400D03*
X46200Y111200D03*
X15857Y202417D03*
X47300Y168700D03*
X15007Y163581D03*
X51400Y168300D03*
X16253Y180320D03*
X20539Y163381D03*
X9581Y160069D03*
X11840Y177692D03*
X4100Y294900D03*
X60300Y290000D03*
X17100Y278300D03*
X13650Y278350D03*
X26270Y282547D03*
X22820Y282597D03*
X18600Y338800D03*
X4200Y312100D03*
Y329000D03*
X42800Y338500D03*
X29000Y338600D03*
X60400Y305900D03*
X60500Y316400D03*
X60300Y331800D03*
X60400Y350300D03*
X44000Y350200D03*
X20100Y350300D03*
X4400D03*
X99300Y25700D03*
X136439Y31761D03*
X132500Y41200D03*
X79000Y43600D03*
X75100Y63900D03*
X118100Y45000D03*
X104900Y21400D03*
X114900Y39900D03*
X97200Y44150D03*
X132600Y53800D03*
X119200Y30900D03*
X97500Y36600D03*
X97400Y29300D03*
X132600Y29600D03*
X124300Y22600D03*
X76900Y15500D03*
X73838Y12100D03*
X126742Y15658D03*
X82200Y60800D03*
X100100Y56300D03*
X125700Y26500D03*
X75600Y87000D03*
Y91500D03*
X79750Y76600D03*
X79604Y86869D03*
X219300Y-13900D03*
X208500Y-22000D03*
X204340Y71660D03*
X186200Y14900D03*
X222500Y35100D03*
X208500Y9400D03*
X203300Y14800D03*
X217800Y14300D03*
X169750Y62500D03*
X163452Y32350D03*
X161300Y51500D03*
X174300Y52000D03*
X172800Y44950D03*
X182800Y46500D03*
X220732Y46039D03*
X194560Y53277D03*
X218300Y32700D03*
X222609Y53150D03*
X179093Y38185D03*
X163000Y43800D03*
X179500Y42750D03*
X178843Y59000D03*
X188250Y66000D03*
X207293Y45526D03*
X211900Y24800D03*
X194560Y56777D03*
X160800Y72000D03*
X154444Y72036D03*
X208900Y59000D03*
X160794Y86162D03*
X219000Y104060D03*
X211000Y140500D03*
X174600Y86980D03*
X198100Y104000D03*
X184700Y112500D03*
X218350Y111900D03*
X204818Y118400D03*
X210276Y122000D03*
X192500Y73385D03*
X218700Y132335D03*
X219000Y107560D03*
X214500Y112000D03*
X192691Y84234D03*
X214800Y128309D03*
X193500Y135835D03*
X190900Y112200D03*
X159711Y82091D03*
X156891Y79378D03*
X184900Y106300D03*
X171263Y92837D03*
X214119Y216661D03*
X224000Y210584D03*
X207750Y224016D03*
X220200Y151000D03*
X219269Y216635D03*
X214401Y281884D03*
X215411Y270499D03*
X209506Y229990D03*
X215916Y232222D03*
X222500Y344500D03*
X200200Y343900D03*
X188300Y343400D03*
X193300Y337900D03*
X211900Y337500D03*
X219900Y330500D03*
X214200Y325100D03*
X209500Y350300D03*
X188000D03*
X172300Y337600D03*
Y350200D03*
X220550Y306050D03*
X224000Y306000D03*
X228400Y-21400D03*
X228600Y42000D03*
X228300Y6100D03*
X228400Y22800D03*
X228600Y69200D03*
Y85900D03*
X227800Y322200D03*
X228500Y337100D03*
X228400Y350200D03*
X650246Y398761D03*
G54D14*
X37283Y173228D03*
X27283D03*
X193583D03*
X183583D03*
X650246Y286361D03*
G54D15*
X38189Y220472D03*
X28346Y222440D03*
X38189Y251968D03*
Y244094D03*
Y236220D03*
Y228346D03*
X28346Y232283D03*
Y240157D03*
Y250000D03*
X12598Y312992D03*
X51968D03*
X198426Y220472D03*
X188583Y222440D03*
X198426Y251968D03*
Y244094D03*
Y236220D03*
Y228346D03*
X188583Y232283D03*
Y240157D03*
Y250000D03*
X172835Y312992D03*
X212205D03*
X650246Y314461D03*
G54D16*
X40157Y211023D03*
X24409D03*
X40157Y261417D03*
X24409D03*
X200394Y211023D03*
X184646D03*
X200394Y261417D03*
X184646D03*
X650246Y230161D03*
G54D17*
X16977Y244294D03*
X16984Y248748D03*
X96200Y16400D03*
X133200Y17751D03*
X107506Y16719D03*
X116430Y16569D03*
X191391Y278906D03*
X195939Y278959D03*
X650246Y342561D03*
G54D18*
X22440Y303149D03*
X32283D03*
X42126D03*
X22440Y322835D03*
X32283D03*
X42126D03*
X182677Y303149D03*
X192520D03*
X202363D03*
X182677Y322835D03*
X192520D03*
X202363D03*
X650246Y258261D03*
G54D19*
X116339Y78740D03*
X650246Y202061D03*
M02*
